FILE_TYPE = MACRO_DRAWING;
SET COLOR_WIRE YELLOW;
SET COLOR_PROP MONO;
SET COLOR_DOT WHITE;
SET COLOR_ARC YELLOW;
SET COLOR_BODY GREEN;
SET COLOR_NOTE MONO;
SET PROP_DISPLAY VALUE;
SET PAGE_NUMBER P220;
FORCEADD PVDDQ_DEF..1
(2675 1950);
FORCEPROP 3 LASTPIN (2675 1900) SIG_NAME PVDDQ_DEF\g
J 0
(2685 1910);
DISPLAY 0.659574 (2685 1910);
PAINT MONO (2685 1910);
DISPLAY INVISIBLE (2685 1910);
FORCEPROP 1 LAST VOLTAGE 1.2V
J 0
(2630 1907);
DISPLAY 0.340426 (2630 1907);
PAINT SKYBLUE (2630 1907);
DISPLAY INVISIBLE (2630 1907);
FORCEPROP 1 LAST HDL_POWER PVDDQ_DEF
J 1
(2675 2000);
DISPLAY 0.872340 (2675 2000);
PAINT GREEN (2675 2000);
DISPLAY INVISIBLE (2675 2000);
FORCEPROP 2 LAST CDS_LIB mstr_symbols
J 0
(2675 1950);
PAINT ORANGE (2675 1950);
DISPLAY INVISIBLE (2675 1950);
FORCEPROP 1 LAST BODY_TYPE PLUMBING
J 0
(2630 1907);
DISPLAY 0.340426 (2630 1907);
PAINT GREEN (2630 1907);
DISPLAY INVISIBLE (2630 1907);
FORCEPROP 1 LAST PATH I109
J 0
(2725 1975);
DISPLAY 0.872340 (2725 1975);
PAINT AQUA (2725 1975);
DISPLAY INVISIBLE (2725 1975);
FORCEPROP 2 LAST BOM_COST MEM_VRD_PVDDQ_DEF
J 0
(2750 2050);
PAINT MONO (2750 2050);
DISPLAY INVISIBLE (2750 2050);
FORCEPROP 2 LAST ROOM VDDQ_DEF_PWR_VR
J 0
(2925 2050);
PAINT ORANGE (2925 2050);
DISPLAY INVISIBLE (2925 2050);
FORCEADD CAP..1
(2400 2825);
FORCEPROP 1 LAST MATERIAL X5R
J 0
(2450 2725);
DISPLAY 0.617021 (2450 2725);
PAINT SKYBLUE (2450 2725);
FORCEPROP 1 LASTPIN (2400 2725) $PN 2
J 0
(2410 2705);
DISPLAY 0.617021 (2410 2705);
PAINT ORANGE (2410 2705);
FORCEPROP 1 LAST TOLERANCE 20%
J 0
(2450 2775);
DISPLAY 0.617021 (2450 2775);
PAINT SKYBLUE (2450 2775);
FORCEPROP 1 LASTPIN (2400 2925) $PN 1
J 0
(2410 2905);
DISPLAY 0.617021 (2410 2905);
PAINT ORANGE (2410 2905);
FORCEPROP 1 LAST VOLTAGE 4V
J 0
(2450 2825);
DISPLAY 0.617021 (2450 2825);
PAINT SKYBLUE (2450 2825);
FORCEPROP 1 LAST PACK_TYPE 0805
J 0
(2450 2625);
DISPLAY 0.617021 (2450 2625);
PAINT SKYBLUE (2450 2625);
FORCEPROP 1 LAST VALUE 100UF
J 0
(2450 2875);
DISPLAY 0.617021 (2450 2875);
PAINT SKYBLUE (2450 2875);
FORCEPROP 1 LAST PART_NUMBER 602433-112
J 0
(2450 2675);
DISPLAY 0.617021 (2450 2675);
PAINT BLUE (2450 2675);
FORCEPROP 1 LAST LOCATION C5A10
J 0
(2450 2925);
DISPLAY 0.617021 (2450 2925);
PAINT AQUA (2450 2925);
FORCEPROP 2 LAST CDS_LIB mstr_discrete
J 0
(2400 2825);
PAINT MONO (2400 2825);
DISPLAY INVISIBLE (2400 2825);
FORCEPROP 2 LAST SEC_TYPE 0805
J 0
(2450 3025);
DISPLAY 1.021277 (2450 3025);
PAINT ORANGE (2450 3025);
DISPLAY INVISIBLE (2450 3025);
FORCEPROP 2 LAST BOM_COST MEM_VRD_PVDDQ_DEF
J 0
(2450 2975);
PAINT MONO (2450 2975);
DISPLAY INVISIBLE (2450 2975);
FORCEPROP 2 LAST SEC 1
J 0
(2450 3025);
DISPLAY 0.680851 (2450 3025);
PAINT MONO (2450 3025);
DISPLAY INVISIBLE (2450 3025);
FORCEPROP 1 LAST PATH I110
J 0
(2450 2975);
DISPLAY 0.978723 (2450 2975);
PAINT WHITE (2450 2975);
DISPLAY INVISIBLE (2450 2975);
FORCEPROP 2 LAST CDS_LOCATION C5A10
J 0
(2450 2925);
DISPLAY 0.617021 (2450 2925);
PAINT AQUA (2450 2925);
DISPLAY INVISIBLE (2450 2925);
FORCEPROP 2 LAST ROOM VDDQ_DEF_PWR_VR
J 0
(2450 2975);
PAINT MONO (2450 2975);
DISPLAY INVISIBLE (2450 2975);
FORCEADD GND..1
(4400 1300);
FORCEPROP 3 LASTPIN (4400 1350) SIG_NAME GND\g
J 0
(4410 1360);
DISPLAY 0.659574 (4410 1360);
PAINT MONO (4410 1360);
DISPLAY INVISIBLE (4410 1360);
FORCEPROP 2 LAST BOM_COST MEM_VRD_PVDDQ_DEF
J 0
(4075 1375);
PAINT MONO (4075 1375);
DISPLAY INVISIBLE (4075 1375);
FORCEPROP 2 LAST ROOM VDDQ_DEF_PWR_VR
J 0
(3850 1375);
PAINT ORANGE (3850 1375);
DISPLAY INVISIBLE (3850 1375);
FORCEPROP 1 LAST BODY_TYPE PLUMBING
J 0
(4355 1257);
DISPLAY 0.340426 (4355 1257);
PAINT GREEN (4355 1257);
DISPLAY INVISIBLE (4355 1257);
FORCEPROP 1 LAST SIZE 1B
J 0
(4475 1250);
DISPLAY 0.893617 (4475 1250);
PAINT GREEN (4475 1250);
DISPLAY INVISIBLE (4475 1250);
FORCEPROP 1 LAST PATH I114
J 0
(4475 1300);
DISPLAY 1.170213 (4475 1300);
PAINT AQUA (4475 1300);
DISPLAY INVISIBLE (4475 1300);
FORCEPROP 2 LAST CDS_LIB mstr_symbols
J 0
(4400 1300);
PAINT ORANGE (4400 1300);
DISPLAY INVISIBLE (4400 1300);
FORCEPROP 1 LAST VOLTAGE 0
J 0
(4400 1300);
PAINT SKYBLUE (4400 1300);
DISPLAY INVISIBLE (4400 1300);
FORCEPROP 1 LAST HDL_POWER GND
J 0
(4400 1450);
DISPLAY 0.893617 (4400 1450);
PAINT GREEN (4400 1450);
DISPLAY INVISIBLE (4400 1450);
FORCEADD VCC_CORE..1
(-1050 1375);
FORCEPROP 3 LASTPIN (-1050 1325) SIG_NAME VR_FET_SW_P12V_STBY_PVDDQ_DEF\g
J 0
(-1040 1335);
DISPLAY 0.659574 (-1040 1335);
PAINT MONO (-1040 1335);
DISPLAY INVISIBLE (-1040 1335);
FORCEPROP 1 LAST HDL_POWER VR_FET_SW_P12V_STBY_PVDDQ_DEF
J 1
(-1050 1425);
DISPLAY 0.617021 (-1050 1425);
PAINT GREEN (-1050 1425);
FORCEPROP 2 LAST CDS_LIB mstr_symbols
J 0
(-1050 1375);
PAINT ORANGE (-1050 1375);
DISPLAY INVISIBLE (-1050 1375);
FORCEPROP 1 LAST PATH I120
J 0
(-1000 1400);
DISPLAY 1.170213 (-1000 1400);
PAINT AQUA (-1000 1400);
DISPLAY INVISIBLE (-1000 1400);
FORCEADD GND..1
(-1050 700);
FORCEPROP 3 LASTPIN (-1050 750) SIG_NAME GND\g
J 0
(-1040 760);
DISPLAY 0.659574 (-1040 760);
PAINT MONO (-1040 760);
DISPLAY INVISIBLE (-1040 760);
FORCEPROP 2 LAST ROOM VDDQ_DEF_PWR_VR
J 0
(-1600 775);
PAINT ORANGE (-1600 775);
DISPLAY INVISIBLE (-1600 775);
FORCEPROP 2 LAST BOM_COST MEM_VRD_PVDDQ_DEF
J 0
(-1375 775);
PAINT MONO (-1375 775);
DISPLAY INVISIBLE (-1375 775);
FORCEPROP 1 LAST BODY_TYPE PLUMBING
J 0
(-1095 657);
DISPLAY 0.340426 (-1095 657);
PAINT GREEN (-1095 657);
DISPLAY INVISIBLE (-1095 657);
FORCEPROP 2 LAST CDS_LIB mstr_symbols
J 0
(-1050 700);
PAINT ORANGE (-1050 700);
DISPLAY INVISIBLE (-1050 700);
FORCEPROP 1 LAST VOLTAGE 0
J 0
(-1050 700);
PAINT SKYBLUE (-1050 700);
DISPLAY INVISIBLE (-1050 700);
FORCEPROP 1 LAST HDL_POWER GND
J 0
(-1050 850);
DISPLAY 0.893617 (-1050 850);
PAINT GREEN (-1050 850);
DISPLAY INVISIBLE (-1050 850);
FORCEPROP 1 LAST PATH I123
J 0
(-975 700);
DISPLAY 1.170213 (-975 700);
PAINT AQUA (-975 700);
DISPLAY INVISIBLE (-975 700);
FORCEPROP 1 LAST SIZE 1B
J 0
(-975 650);
DISPLAY 0.893617 (-975 650);
PAINT GREEN (-975 650);
DISPLAY INVISIBLE (-975 650);
FORCEADD INDUCTOR..1
(-1475 1125);
FORCEPROP 1 LASTPIN (-1575 1125) $PN 1
J 0
(-1575 1135);
DISPLAY 0.617021 (-1575 1135);
PAINT WHITE (-1575 1135);
FORCEPROP 1 LAST VALUE 100NH
J 2
(-1480 1040);
DISPLAY 0.617021 (-1480 1040);
PAINT SKYBLUE (-1480 1040);
FORCEPROP 1 LAST PART_NUMBER D92183-020
J 0
(-1575 1225);
DISPLAY 0.617021 (-1575 1225);
PAINT BLUE (-1575 1225);
FORCEPROP 1 LAST LOCATION L7A5
J 0
(-1575 1175);
DISPLAY 0.617021 (-1575 1175);
PAINT AQUA (-1575 1175);
FORCEPROP 1 LAST MATERIAL IND
J 0
(-1460 1040);
DISPLAY 0.617021 (-1460 1040);
PAINT SKYBLUE (-1460 1040);
FORCEPROP 1 LASTPIN (-1375 1125) $PN 2
J 2
(-1365 1135);
DISPLAY 0.617021 (-1365 1135);
PAINT WHITE (-1365 1135);
FORCEPROP 1 LAST PACK_TYPE SM
J 0
(-1185 1040);
DISPLAY 0.617021 (-1185 1040);
PAINT SKYBLUE (-1185 1040);
FORCEPROP 2 LAST CDS_LOCATION L7A5
J 0
(-1575 1175);
DISPLAY 0.617021 (-1575 1175);
PAINT AQUA (-1575 1175);
DISPLAY INVISIBLE (-1575 1175);
FORCEPROP 2 LAST BOM_COST MEM_VRD_PVDDQ_DEF
J 0
(-1575 1275);
PAINT MONO (-1575 1275);
DISPLAY INVISIBLE (-1575 1275);
FORCEPROP 1 LAST PATH I124
J 0
(-1575 1275);
DISPLAY 1.319149 (-1575 1275);
PAINT ORANGE (-1575 1275);
DISPLAY INVISIBLE (-1575 1275);
FORCEPROP 2 LAST ROOM VDDQ_DEF_PWR_VR
J 0
(-1575 1275);
PAINT MONO (-1575 1275);
DISPLAY INVISIBLE (-1575 1275);
FORCEPROP 2 LAST SEC_TYPE SM
J 0
(-1570 1345);
DISPLAY 1.021277 (-1570 1345);
PAINT ORANGE (-1570 1345);
DISPLAY INVISIBLE (-1570 1345);
FORCEPROP 2 LAST SEC 1
J 0
(-1570 1345);
DISPLAY 0.680851 (-1570 1345);
PAINT MONO (-1570 1345);
DISPLAY INVISIBLE (-1570 1345);
FORCEPROP 2 LAST CDS_LIB mstr_discrete
J 0
(-1475 1125);
PAINT ORANGE (-1475 1125);
DISPLAY INVISIBLE (-1475 1125);
FORCEADD CAPP..1
(-1050 925);
FORCEPROP 1 LASTPIN (-1050 1025) $PN 1
J 0
(-1040 1010);
DISPLAY 0.617021 (-1040 1010);
PAINT ORANGE (-1040 1010);
FORCEPROP 1 LASTPIN (-1050 825) $PN 2
J 0
(-1040 810);
DISPLAY 0.617021 (-1040 810);
PAINT ORANGE (-1040 810);
FORCEPROP 1 LAST MATERIAL OSCON
J 0
(-1000 825);
DISPLAY 0.617021 (-1000 825);
PAINT SKYBLUE (-1000 825);
FORCEPROP 1 LAST VOLTAGE 16V
J 0
(-1000 875);
DISPLAY 0.617021 (-1000 875);
PAINT SKYBLUE (-1000 875);
FORCEPROP 1 LAST PACK_TYPE 2626
J 0
(-1000 775);
DISPLAY 0.617021 (-1000 775);
PAINT SKYBLUE (-1000 775);
FORCEPROP 1 LAST TOLERANCE 20%
J 0
(-1000 925);
DISPLAY 0.617021 (-1000 925);
PAINT SKYBLUE (-1000 925);
FORCEPROP 1 LAST VALUE 270UF
J 0
(-1000 975);
DISPLAY 0.617021 (-1000 975);
PAINT SKYBLUE (-1000 975);
FORCEPROP 1 LAST PART_NUMBER A31228-047
J 0
(-1000 725);
DISPLAY 0.617021 (-1000 725);
PAINT BLUE (-1000 725);
FORCEPROP 1 LAST LOCATION C7A19
J 0
(-1000 1025);
DISPLAY 0.617021 (-1000 1025);
PAINT AQUA (-1000 1025);
FORCEPROP 2 LAST CDS_LIB mstr_discrete
J 0
(-1050 925);
PAINT ORANGE (-1050 925);
DISPLAY INVISIBLE (-1050 925);
FORCEPROP 1 LAST PATH I175
J 0
(-1000 1075);
DISPLAY 1.319149 (-1000 1075);
PAINT ORANGE (-1000 1075);
DISPLAY INVISIBLE (-1000 1075);
FORCEPROP 2 LAST CDS_LOCATION C7A19
J 0
(-1000 1025);
DISPLAY 0.617021 (-1000 1025);
PAINT AQUA (-1000 1025);
DISPLAY INVISIBLE (-1000 1025);
FORCEPROP 2 LAST SEC 1
J 0
(-1000 1150);
DISPLAY 0.680851 (-1000 1150);
PAINT MONO (-1000 1150);
DISPLAY INVISIBLE (-1000 1150);
FORCEPROP 2 LAST SEC_TYPE 2626
J 0
(-1000 1150);
DISPLAY 1.021277 (-1000 1150);
PAINT ORANGE (-1000 1150);
DISPLAY INVISIBLE (-1000 1150);
FORCEPROP 2 LAST ROOM VDDQ_DEF_PWR_VR
J 0
(-1000 1075);
DISPLAY 1.361702 (-1000 1075);
PAINT ORANGE (-1000 1075);
DISPLAY INVISIBLE (-1000 1075);
FORCEADD P12V_STBY..1
(-1700 1425);
FORCEPROP 3 LASTPIN (-1700 1375) SIG_NAME P12V_STBY\g
J 0
(-1690 1385);
DISPLAY 0.659574 (-1690 1385);
PAINT MONO (-1690 1385);
DISPLAY INVISIBLE (-1690 1385);
FORCEPROP 1 LAST HDL_POWER P12V_STBY
J 0
(-2000 1300);
DISPLAY 0.872340 (-2000 1300);
PAINT ORANGE (-2000 1300);
DISPLAY INVISIBLE (-2000 1300);
FORCEPROP 1 LAST PATH I176
J 0
(-1655 1427);
DISPLAY 0.340426 (-1655 1427);
PAINT GREEN (-1655 1427);
DISPLAY INVISIBLE (-1655 1427);
FORCEPROP 1 LAST BODY_TYPE PLUMBING
J 0
(-1745 1382);
DISPLAY 0.340426 (-1745 1382);
PAINT GREEN (-1745 1382);
DISPLAY INVISIBLE (-1745 1382);
FORCEPROP 2 LAST CDS_LIB mstr_symbols
J 0
(-1700 1425);
PAINT ORANGE (-1700 1425);
DISPLAY INVISIBLE (-1700 1425);
FORCEPROP 1 LAST SIZE 1B
J 0
(-1655 1447);
DISPLAY 0.340426 (-1655 1447);
PAINT GREEN (-1655 1447);
DISPLAY INVISIBLE (-1655 1447);
FORCEPROP 1 LAST VOLTAGE 12.0V
J 0
(-1745 1382);
DISPLAY 0.340426 (-1745 1382);
PAINT SKYBLUE (-1745 1382);
DISPLAY INVISIBLE (-1745 1382);
FORCEADD CAP..1
(-2225 2900);
FORCEPROP 1 LASTPIN (-2225 2800) $PN 2
J 0
(-2215 2780);
DISPLAY 0.617021 (-2215 2780);
PAINT ORANGE (-2215 2780);
FORCEPROP 1 LAST MATERIAL X6S
J 0
(-2175 2800);
DISPLAY 0.617021 (-2175 2800);
PAINT SKYBLUE (-2175 2800);
FORCEPROP 1 LAST LOCATION C5P2
J 0
(-2175 3000);
DISPLAY 0.617021 (-2175 3000);
PAINT AQUA (-2175 3000);
FORCEPROP 1 LASTPIN (-2225 3000) $PN 1
J 0
(-2215 2980);
DISPLAY 0.617021 (-2215 2980);
PAINT ORANGE (-2215 2980);
FORCEPROP 1 LAST TOLERANCE 20%
J 0
(-2175 2850);
DISPLAY 0.617021 (-2175 2850);
PAINT SKYBLUE (-2175 2850);
FORCEPROP 1 LAST VALUE 22UF
J 0
(-2175 2950);
DISPLAY 0.617021 (-2175 2950);
PAINT SKYBLUE (-2175 2950);
FORCEPROP 1 LAST PACK_TYPE 0805LF
J 0
(-2175 2700);
DISPLAY 0.617021 (-2175 2700);
PAINT SKYBLUE (-2175 2700);
FORCEPROP 1 LAST PART_NUMBER C95333-002
J 0
(-2175 2750);
DISPLAY 0.617021 (-2175 2750);
PAINT BLUE (-2175 2750);
FORCEPROP 2 LAST CDS_LIB mstr_discrete
J 0
(-2225 2900);
PAINT ORANGE (-2225 2900);
DISPLAY INVISIBLE (-2225 2900);
FORCEPROP 2 LAST CDS_LOCATION C5P2
J 0
(-2175 3000);
DISPLAY 0.617021 (-2175 3000);
PAINT AQUA (-2175 3000);
DISPLAY INVISIBLE (-2175 3000);
FORCEPROP 1 LAST VOLTAGE 4V
J 0
(-2175 2900);
PAINT SKYBLUE (-2175 2900);
DISPLAY INVISIBLE (-2175 2900);
FORCEPROP 1 LAST PATH I177
J 0
(-2175 3050);
DISPLAY 0.978723 (-2175 3050);
PAINT WHITE (-2175 3050);
DISPLAY INVISIBLE (-2175 3050);
FORCEPROP 2 LAST BOM_COST MEM_VRD_PVDDQ_DEF
J 0
(-2175 3050);
PAINT MONO (-2175 3050);
DISPLAY INVISIBLE (-2175 3050);
FORCEPROP 2 LAST ROOM VDDQ_DEF_CPU0
J 0
(-2175 3050);
PAINT MONO (-2175 3050);
DISPLAY INVISIBLE (-2175 3050);
FORCEPROP 2 LAST SEC_TYPE 0805LF
J 0
(-2175 3100);
DISPLAY 1.021277 (-2175 3100);
PAINT ORANGE (-2175 3100);
DISPLAY INVISIBLE (-2175 3100);
FORCEPROP 2 LAST SEC 1
J 0
(-2175 3100);
DISPLAY 0.680851 (-2175 3100);
PAINT MONO (-2175 3100);
DISPLAY INVISIBLE (-2175 3100);
FORCEADD CAP..1
(-1875 2900);
FORCEPROP 1 LASTPIN (-1875 2800) $PN 2
J 0
(-1865 2780);
DISPLAY 0.617021 (-1865 2780);
PAINT ORANGE (-1865 2780);
FORCEPROP 1 LASTPIN (-1875 3000) $PN 1
J 0
(-1865 2980);
DISPLAY 0.617021 (-1865 2980);
PAINT ORANGE (-1865 2980);
FORCEPROP 1 LAST TOLERANCE 20%
J 0
(-1825 2850);
DISPLAY 0.617021 (-1825 2850);
PAINT SKYBLUE (-1825 2850);
FORCEPROP 1 LAST PACK_TYPE 0805LF
J 0
(-1825 2700);
DISPLAY 0.617021 (-1825 2700);
PAINT SKYBLUE (-1825 2700);
FORCEPROP 1 LAST MATERIAL X6S
J 0
(-1825 2800);
DISPLAY 0.617021 (-1825 2800);
PAINT SKYBLUE (-1825 2800);
FORCEPROP 1 LAST VALUE 22UF
J 0
(-1825 2950);
DISPLAY 0.617021 (-1825 2950);
PAINT SKYBLUE (-1825 2950);
FORCEPROP 1 LAST LOCATION C5P1
J 0
(-1825 3000);
DISPLAY 0.617021 (-1825 3000);
PAINT AQUA (-1825 3000);
FORCEPROP 1 LAST PART_NUMBER C95333-002
J 0
(-1825 2750);
DISPLAY 0.617021 (-1825 2750);
PAINT BLUE (-1825 2750);
FORCEPROP 1 LAST VOLTAGE 4V
J 0
(-1825 2900);
PAINT SKYBLUE (-1825 2900);
DISPLAY INVISIBLE (-1825 2900);
FORCEPROP 2 LAST CDS_LIB mstr_discrete
J 0
(-1875 2900);
PAINT ORANGE (-1875 2900);
DISPLAY INVISIBLE (-1875 2900);
FORCEPROP 2 LAST CDS_LOCATION C5P1
J 0
(-1825 3000);
DISPLAY 0.617021 (-1825 3000);
PAINT AQUA (-1825 3000);
DISPLAY INVISIBLE (-1825 3000);
FORCEPROP 1 LAST PATH I179
J 0
(-1825 3050);
DISPLAY 0.978723 (-1825 3050);
PAINT WHITE (-1825 3050);
DISPLAY INVISIBLE (-1825 3050);
FORCEPROP 2 LAST BOM_COST MEM_VRD_PVDDQ_DEF
J 0
(-1825 3050);
PAINT MONO (-1825 3050);
DISPLAY INVISIBLE (-1825 3050);
FORCEPROP 2 LAST ROOM VDDQ_DEF_CPU0
J 0
(-1825 3050);
PAINT MONO (-1825 3050);
DISPLAY INVISIBLE (-1825 3050);
FORCEPROP 2 LAST SEC 1
J 0
(-1825 3100);
DISPLAY 0.680851 (-1825 3100);
PAINT MONO (-1825 3100);
DISPLAY INVISIBLE (-1825 3100);
FORCEPROP 2 LAST SEC_TYPE 0805LF
J 0
(-1825 3100);
DISPLAY 1.021277 (-1825 3100);
PAINT ORANGE (-1825 3100);
DISPLAY INVISIBLE (-1825 3100);
FORCEADD CAP..1
(-1475 2900);
FORCEPROP 1 LASTPIN (-1475 2800) $PN 2
J 0
(-1465 2780);
DISPLAY 0.617021 (-1465 2780);
PAINT ORANGE (-1465 2780);
FORCEPROP 1 LAST MATERIAL X6S
J 0
(-1425 2800);
DISPLAY 0.617021 (-1425 2800);
PAINT SKYBLUE (-1425 2800);
FORCEPROP 1 LAST LOCATION C5D9
J 0
(-1425 3000);
DISPLAY 0.617021 (-1425 3000);
PAINT AQUA (-1425 3000);
FORCEPROP 1 LAST VALUE 10UF
J 0
(-1425 2950);
DISPLAY 0.617021 (-1425 2950);
PAINT SKYBLUE (-1425 2950);
FORCEPROP 1 LAST TOLERANCE 20%
J 0
(-1425 2850);
DISPLAY 0.617021 (-1425 2850);
PAINT SKYBLUE (-1425 2850);
FORCEPROP 1 LAST VOLTAGE 4V
J 0
(-1425 2900);
DISPLAY 0.617021 (-1425 2900);
PAINT SKYBLUE (-1425 2900);
FORCEPROP 1 LASTPIN (-1475 3000) $PN 1
J 0
(-1465 2980);
DISPLAY 0.617021 (-1465 2980);
PAINT ORANGE (-1465 2980);
FORCEPROP 1 LAST PART_NUMBER E15431-001
J 0
(-1425 2750);
DISPLAY 0.617021 (-1425 2750);
PAINT BLUE (-1425 2750);
FORCEPROP 1 LAST PACK_TYPE 0603LF
J 0
(-1425 2700);
DISPLAY 0.617021 (-1425 2700);
PAINT SKYBLUE (-1425 2700);
FORCEPROP 2 LAST CDS_LIB mstr_discrete
J 0
(-1475 2900);
PAINT ORANGE (-1475 2900);
DISPLAY INVISIBLE (-1475 2900);
FORCEPROP 2 LAST CDS_LOCATION C5D9
J 0
(-1425 3000);
DISPLAY 0.617021 (-1425 3000);
PAINT AQUA (-1425 3000);
DISPLAY INVISIBLE (-1425 3000);
FORCEPROP 1 LAST PATH I180
J 0
(-1425 3050);
DISPLAY 0.978723 (-1425 3050);
PAINT WHITE (-1425 3050);
DISPLAY INVISIBLE (-1425 3050);
FORCEPROP 2 LAST BOM_COST MEM_VRD_PVDDQ_DEF
J 0
(-1425 3050);
PAINT MONO (-1425 3050);
DISPLAY INVISIBLE (-1425 3050);
FORCEPROP 2 LAST ROOM VDDQ_DEF_CPU0
J 0
(-1425 3050);
PAINT MONO (-1425 3050);
DISPLAY INVISIBLE (-1425 3050);
FORCEPROP 2 LAST SEC_TYPE 0603LF
J 0
(-1425 3100);
DISPLAY 1.021277 (-1425 3100);
PAINT ORANGE (-1425 3100);
DISPLAY INVISIBLE (-1425 3100);
FORCEPROP 2 LAST SEC 1
J 0
(-1425 3100);
DISPLAY 0.680851 (-1425 3100);
PAINT MONO (-1425 3100);
DISPLAY INVISIBLE (-1425 3100);
FORCEADD GND..1
(-425 2550);
FORCEPROP 3 LASTPIN (-425 2600) SIG_NAME GND\g
J 0
(-415 2610);
DISPLAY 0.659574 (-415 2610);
PAINT MONO (-415 2610);
DISPLAY INVISIBLE (-415 2610);
FORCEPROP 2 LAST ROOM VDDQ_ABC_PWR_VR
J 0
(-975 2625);
PAINT ORANGE (-975 2625);
DISPLAY INVISIBLE (-975 2625);
FORCEPROP 2 LAST BOM_COST MEM_VRD_PVDDQ_CD
J 0
(-750 2625);
PAINT MONO (-750 2625);
DISPLAY INVISIBLE (-750 2625);
FORCEPROP 1 LAST BODY_TYPE PLUMBING
J 0
(-470 2507);
DISPLAY 0.340426 (-470 2507);
PAINT GREEN (-470 2507);
DISPLAY INVISIBLE (-470 2507);
FORCEPROP 1 LAST SIZE 1B
J 0
(-350 2500);
DISPLAY 0.893617 (-350 2500);
PAINT GREEN (-350 2500);
DISPLAY INVISIBLE (-350 2500);
FORCEPROP 1 LAST PATH I181
J 0
(-350 2550);
DISPLAY 0.872340 (-350 2550);
PAINT AQUA (-350 2550);
DISPLAY INVISIBLE (-350 2550);
FORCEPROP 2 LAST CDS_LIB mstr_symbols
J 0
(-425 2550);
PAINT ORANGE (-425 2550);
DISPLAY INVISIBLE (-425 2550);
FORCEPROP 1 LAST VOLTAGE 0
J 0
(-425 2550);
PAINT SKYBLUE (-425 2550);
DISPLAY INVISIBLE (-425 2550);
FORCEPROP 1 LAST HDL_POWER GND
J 0
(-425 2700);
DISPLAY 0.893617 (-425 2700);
PAINT GREEN (-425 2700);
DISPLAY INVISIBLE (-425 2700);
FORCEADD CAP..1
(-1125 2900);
FORCEPROP 1 LASTPIN (-1125 2800) $PN 2
J 0
(-1115 2780);
DISPLAY 0.617021 (-1115 2780);
PAINT ORANGE (-1115 2780);
FORCEPROP 1 LASTPIN (-1125 3000) $PN 1
J 0
(-1115 2980);
DISPLAY 0.617021 (-1115 2980);
PAINT ORANGE (-1115 2980);
FORCEPROP 1 LAST MATERIAL X6S
J 0
(-1075 2800);
DISPLAY 0.617021 (-1075 2800);
PAINT SKYBLUE (-1075 2800);
FORCEPROP 1 LAST VOLTAGE 4V
J 0
(-1075 2900);
DISPLAY 0.617021 (-1075 2900);
PAINT SKYBLUE (-1075 2900);
FORCEPROP 1 LAST PACK_TYPE 0603LF
J 0
(-1075 2700);
DISPLAY 0.617021 (-1075 2700);
PAINT SKYBLUE (-1075 2700);
FORCEPROP 1 LAST TOLERANCE 20%
J 0
(-1075 2850);
DISPLAY 0.617021 (-1075 2850);
PAINT SKYBLUE (-1075 2850);
FORCEPROP 1 LAST PART_NUMBER E15431-001
J 0
(-1075 2750);
DISPLAY 0.617021 (-1075 2750);
PAINT BLUE (-1075 2750);
FORCEPROP 1 LAST LOCATION C5D6
J 0
(-1075 3000);
DISPLAY 0.617021 (-1075 3000);
PAINT AQUA (-1075 3000);
FORCEPROP 1 LAST VALUE 10UF
J 0
(-1075 2950);
DISPLAY 0.617021 (-1075 2950);
PAINT SKYBLUE (-1075 2950);
FORCEPROP 2 LAST CDS_LIB mstr_discrete
J 0
(-1125 2900);
PAINT ORANGE (-1125 2900);
DISPLAY INVISIBLE (-1125 2900);
FORCEPROP 2 LAST CDS_LOCATION C5D6
J 0
(-1075 3000);
DISPLAY 0.617021 (-1075 3000);
PAINT AQUA (-1075 3000);
DISPLAY INVISIBLE (-1075 3000);
FORCEPROP 1 LAST PATH I182
J 0
(-1075 3050);
DISPLAY 0.978723 (-1075 3050);
PAINT WHITE (-1075 3050);
DISPLAY INVISIBLE (-1075 3050);
FORCEPROP 2 LAST BOM_COST MEM_VRD_PVDDQ_DEF
J 0
(-1075 3050);
PAINT MONO (-1075 3050);
DISPLAY INVISIBLE (-1075 3050);
FORCEPROP 2 LAST ROOM VDDQ_DEF_CPU0
J 0
(-1075 3050);
PAINT MONO (-1075 3050);
DISPLAY INVISIBLE (-1075 3050);
FORCEPROP 2 LAST SEC 1
J 0
(-1075 3100);
DISPLAY 0.680851 (-1075 3100);
PAINT MONO (-1075 3100);
DISPLAY INVISIBLE (-1075 3100);
FORCEPROP 2 LAST SEC_TYPE 0603LF
J 0
(-1075 3100);
DISPLAY 1.021277 (-1075 3100);
PAINT ORANGE (-1075 3100);
DISPLAY INVISIBLE (-1075 3100);
FORCEADD CAP..1
(-775 2900);
FORCEPROP 1 LAST LOCATION C5D7
J 0
(-725 3000);
DISPLAY 0.617021 (-725 3000);
PAINT AQUA (-725 3000);
FORCEPROP 1 LAST VALUE 10UF
J 0
(-725 2950);
DISPLAY 0.617021 (-725 2950);
PAINT SKYBLUE (-725 2950);
FORCEPROP 1 LASTPIN (-775 2800) $PN 2
J 0
(-765 2780);
DISPLAY 0.617021 (-765 2780);
PAINT ORANGE (-765 2780);
FORCEPROP 1 LASTPIN (-775 3000) $PN 1
J 0
(-765 2980);
DISPLAY 0.617021 (-765 2980);
PAINT ORANGE (-765 2980);
FORCEPROP 1 LAST MATERIAL X6S
J 0
(-725 2800);
DISPLAY 0.617021 (-725 2800);
PAINT SKYBLUE (-725 2800);
FORCEPROP 1 LAST VOLTAGE 4V
J 0
(-725 2900);
DISPLAY 0.617021 (-725 2900);
PAINT SKYBLUE (-725 2900);
FORCEPROP 1 LAST PACK_TYPE 0603LF
J 0
(-725 2700);
DISPLAY 0.617021 (-725 2700);
PAINT SKYBLUE (-725 2700);
FORCEPROP 1 LAST TOLERANCE 20%
J 0
(-725 2850);
DISPLAY 0.617021 (-725 2850);
PAINT SKYBLUE (-725 2850);
FORCEPROP 1 LAST PART_NUMBER E15431-001
J 0
(-725 2750);
DISPLAY 0.617021 (-725 2750);
PAINT BLUE (-725 2750);
FORCEPROP 2 LAST CDS_LIB mstr_discrete
J 0
(-775 2900);
PAINT ORANGE (-775 2900);
DISPLAY INVISIBLE (-775 2900);
FORCEPROP 2 LAST CDS_LOCATION C5D7
J 0
(-725 3000);
DISPLAY 0.617021 (-725 3000);
PAINT AQUA (-725 3000);
DISPLAY INVISIBLE (-725 3000);
FORCEPROP 1 LAST PATH I183
J 0
(-725 3050);
DISPLAY 0.978723 (-725 3050);
PAINT WHITE (-725 3050);
DISPLAY INVISIBLE (-725 3050);
FORCEPROP 2 LAST BOM_COST MEM_VRD_PVDDQ_DEF
J 0
(-725 3050);
PAINT MONO (-725 3050);
DISPLAY INVISIBLE (-725 3050);
FORCEPROP 2 LAST ROOM VDDQ_DEF_CPU0
J 0
(-725 3050);
PAINT MONO (-725 3050);
DISPLAY INVISIBLE (-725 3050);
FORCEPROP 2 LAST SEC 1
J 0
(-725 3100);
DISPLAY 0.680851 (-725 3100);
PAINT MONO (-725 3100);
DISPLAY INVISIBLE (-725 3100);
FORCEPROP 2 LAST SEC_TYPE 0603LF
J 0
(-725 3100);
DISPLAY 1.021277 (-725 3100);
PAINT ORANGE (-725 3100);
DISPLAY INVISIBLE (-725 3100);
FORCEADD CAP..1
(-425 2900);
FORCEPROP 1 LASTPIN (-425 2800) $PN 2
J 0
(-415 2780);
DISPLAY 0.617021 (-415 2780);
PAINT ORANGE (-415 2780);
FORCEPROP 1 LAST MATERIAL X6S
J 0
(-375 2800);
DISPLAY 0.617021 (-375 2800);
PAINT SKYBLUE (-375 2800);
FORCEPROP 1 LAST TOLERANCE 20%
J 0
(-375 2850);
DISPLAY 0.617021 (-375 2850);
PAINT SKYBLUE (-375 2850);
FORCEPROP 1 LASTPIN (-425 3000) $PN 1
J 0
(-415 2980);
DISPLAY 0.617021 (-415 2980);
PAINT ORANGE (-415 2980);
FORCEPROP 1 LAST VOLTAGE 4V
J 0
(-375 2900);
DISPLAY 0.617021 (-375 2900);
PAINT SKYBLUE (-375 2900);
FORCEPROP 1 LAST VALUE 10UF
J 0
(-375 2950);
DISPLAY 0.617021 (-375 2950);
PAINT SKYBLUE (-375 2950);
FORCEPROP 1 LAST LOCATION C5D8
J 0
(-375 3000);
DISPLAY 0.617021 (-375 3000);
PAINT AQUA (-375 3000);
FORCEPROP 1 LAST PACK_TYPE 0603LF
J 0
(-375 2700);
DISPLAY 0.617021 (-375 2700);
PAINT SKYBLUE (-375 2700);
FORCEPROP 1 LAST PART_NUMBER E15431-001
J 0
(-375 2750);
DISPLAY 0.617021 (-375 2750);
PAINT BLUE (-375 2750);
FORCEPROP 2 LAST CDS_LOCATION C5D8
J 0
(-375 3000);
DISPLAY 0.617021 (-375 3000);
PAINT AQUA (-375 3000);
DISPLAY INVISIBLE (-375 3000);
FORCEPROP 2 LAST CDS_LIB mstr_discrete
J 0
(-425 2900);
PAINT ORANGE (-425 2900);
DISPLAY INVISIBLE (-425 2900);
FORCEPROP 1 LAST PATH I184
J 0
(-375 3050);
DISPLAY 0.978723 (-375 3050);
PAINT WHITE (-375 3050);
DISPLAY INVISIBLE (-375 3050);
FORCEPROP 2 LAST BOM_COST MEM_VRD_PVDDQ_DEF
J 0
(-375 3050);
PAINT MONO (-375 3050);
DISPLAY INVISIBLE (-375 3050);
FORCEPROP 2 LAST ROOM VDDQ_DEF_CPU0
J 0
(-375 3050);
PAINT MONO (-375 3050);
DISPLAY INVISIBLE (-375 3050);
FORCEPROP 2 LAST SEC 1
J 0
(-375 3100);
DISPLAY 0.680851 (-375 3100);
PAINT MONO (-375 3100);
DISPLAY INVISIBLE (-375 3100);
FORCEPROP 2 LAST SEC_TYPE 0603LF
J 0
(-375 3100);
DISPLAY 1.021277 (-375 3100);
PAINT ORANGE (-375 3100);
DISPLAY INVISIBLE (-375 3100);
FORCEADD PVDDQ_DEF..1
(-2225 3175);
FORCEPROP 3 LASTPIN (-2225 3125) SIG_NAME PVDDQ_DEF\g
J 0
(-2215 3135);
DISPLAY 0.659574 (-2215 3135);
PAINT MONO (-2215 3135);
DISPLAY INVISIBLE (-2215 3135);
FORCEPROP 1 LAST VOLTAGE 1.2V
J 0
(-2270 3132);
DISPLAY 0.340426 (-2270 3132);
PAINT SKYBLUE (-2270 3132);
DISPLAY INVISIBLE (-2270 3132);
FORCEPROP 1 LAST HDL_POWER PVDDQ_DEF
J 1
(-2225 3225);
DISPLAY 0.872340 (-2225 3225);
PAINT GREEN (-2225 3225);
DISPLAY INVISIBLE (-2225 3225);
FORCEPROP 2 LAST CDS_LIB mstr_symbols
J 0
(-2225 3175);
PAINT ORANGE (-2225 3175);
DISPLAY INVISIBLE (-2225 3175);
FORCEPROP 1 LAST BODY_TYPE PLUMBING
J 0
(-2270 3132);
DISPLAY 0.340426 (-2270 3132);
PAINT GREEN (-2270 3132);
DISPLAY INVISIBLE (-2270 3132);
FORCEPROP 2 LAST BOM_COST MEM_VRD_PVPP_DEF
J 0
(-2175 3275);
PAINT MONO (-2175 3275);
DISPLAY INVISIBLE (-2175 3275);
FORCEPROP 1 LAST PATH I185
J 0
(-2175 3200);
DISPLAY 0.872340 (-2175 3200);
PAINT AQUA (-2175 3200);
DISPLAY INVISIBLE (-2175 3200);
FORCEPROP 2 LAST ROOM VDDQ_DEF_PWR_VR
J 0
(-2000 3275);
PAINT ORANGE (-2000 3275);
DISPLAY INVISIBLE (-2000 3275);
FORCEADD PVDDQ_DEF..1
(2650 1225);
FORCEPROP 3 LASTPIN (2650 1175) SIG_NAME PVDDQ_DEF\g
J 0
(2660 1185);
DISPLAY 0.659574 (2660 1185);
PAINT MONO (2660 1185);
DISPLAY INVISIBLE (2660 1185);
FORCEPROP 2 LAST CDS_LIB mstr_symbols
J 0
(2650 1225);
PAINT ORANGE (2650 1225);
DISPLAY INVISIBLE (2650 1225);
FORCEPROP 1 LAST BODY_TYPE PLUMBING
J 0
(2605 1182);
DISPLAY 0.340426 (2605 1182);
PAINT GREEN (2605 1182);
DISPLAY INVISIBLE (2605 1182);
FORCEPROP 1 LAST VOLTAGE 1.2V
J 0
(2605 1182);
DISPLAY 0.340426 (2605 1182);
PAINT SKYBLUE (2605 1182);
DISPLAY INVISIBLE (2605 1182);
FORCEPROP 1 LAST PATH I189
J 0
(2700 1250);
DISPLAY 0.872340 (2700 1250);
PAINT AQUA (2700 1250);
DISPLAY INVISIBLE (2700 1250);
FORCEPROP 1 LAST HDL_POWER PVDDQ_DEF
J 1
(2650 1275);
DISPLAY 0.872340 (2650 1275);
PAINT GREEN (2650 1275);
DISPLAY INVISIBLE (2650 1275);
FORCEPROP 2 LAST BOM_COST MEM_VRD_PVDDQ_DEF
J 0
(2725 1325);
PAINT MONO (2725 1325);
DISPLAY INVISIBLE (2725 1325);
FORCEPROP 2 LAST ROOM VDDQ_DEF_PWR_VR
J 0
(2900 1325);
PAINT ORANGE (2900 1325);
DISPLAY INVISIBLE (2900 1325);
FORCEADD GND..1
(3600 600);
FORCEPROP 3 LASTPIN (3600 650) SIG_NAME GND\g
J 0
(3610 660);
DISPLAY 0.659574 (3610 660);
PAINT MONO (3610 660);
DISPLAY INVISIBLE (3610 660);
FORCEPROP 2 LAST ROOM VDDQ_DEF_PWR_VR
J 0
(3050 675);
PAINT ORANGE (3050 675);
DISPLAY INVISIBLE (3050 675);
FORCEPROP 2 LAST BOM_COST MEM_VRD_PVDDQ_DEF
J 0
(3275 675);
PAINT MONO (3275 675);
DISPLAY INVISIBLE (3275 675);
FORCEPROP 1 LAST BODY_TYPE PLUMBING
J 0
(3555 557);
DISPLAY 0.340426 (3555 557);
PAINT GREEN (3555 557);
DISPLAY INVISIBLE (3555 557);
FORCEPROP 1 LAST VOLTAGE 0
J 0
(3600 600);
PAINT SKYBLUE (3600 600);
DISPLAY INVISIBLE (3600 600);
FORCEPROP 1 LAST HDL_POWER GND
J 0
(3600 750);
DISPLAY 0.893617 (3600 750);
PAINT GREEN (3600 750);
DISPLAY INVISIBLE (3600 750);
FORCEPROP 1 LAST SIZE 1B
J 0
(3675 550);
DISPLAY 0.893617 (3675 550);
PAINT GREEN (3675 550);
DISPLAY INVISIBLE (3675 550);
FORCEPROP 2 LAST CDS_LIB mstr_symbols
J 0
(3600 600);
PAINT ORANGE (3600 600);
DISPLAY INVISIBLE (3600 600);
FORCEPROP 1 LAST PATH I191
J 0
(3675 600);
DISPLAY 0.872340 (3675 600);
PAINT AQUA (3675 600);
DISPLAY INVISIBLE (3675 600);
FORCEADD CAP_A..1
(2650 950);
FORCEPROP 1 LAST MATERIAL X5R
J 0
(2700 850);
DISPLAY 0.617021 (2700 850);
PAINT SKYBLUE (2700 850);
FORCEPROP 1 LASTPIN (2650 850) $PN 2
J 0
(2660 830);
DISPLAY 0.617021 (2660 830);
PAINT ORANGE (2660 830);
FORCEPROP 1 LAST VOLTAGE 4V
J 0
(2700 950);
DISPLAY 0.617021 (2700 950);
PAINT SKYBLUE (2700 950);
FORCEPROP 1 LAST TOLERANCE 20%
J 0
(2700 900);
DISPLAY 0.617021 (2700 900);
PAINT SKYBLUE (2700 900);
FORCEPROP 1 LAST PACK_TYPE 0603V
J 0
(2700 750);
DISPLAY 0.617021 (2700 750);
PAINT SKYBLUE (2700 750);
FORCEPROP 1 LAST PART_NUMBER 602433-106
J 0
(2700 800);
DISPLAY 0.617021 (2700 800);
PAINT BLUE (2700 800);
FORCEPROP 1 LAST VALUE 47UF
J 0
(2700 1000);
DISPLAY 0.617021 (2700 1000);
PAINT SKYBLUE (2700 1000);
FORCEPROP 1 LASTPIN (2650 1050) $PN 1
J 0
(2660 1030);
DISPLAY 0.617021 (2660 1030);
PAINT ORANGE (2660 1030);
FORCEPROP 1 LAST LOCATION C5L15
J 0
(2700 1050);
DISPLAY 0.617021 (2700 1050);
PAINT AQUA (2700 1050);
FORCEPROP 2 LAST CDS_LIB dev_discrete
J 0
(2650 950);
PAINT ORANGE (2650 950);
DISPLAY INVISIBLE (2650 950);
FORCEPROP 1 LAST PATH I192
J 0
(2700 1100);
DISPLAY 0.978723 (2700 1100);
PAINT WHITE (2700 1100);
DISPLAY INVISIBLE (2700 1100);
FORCEPROP 2 LAST SEC 1
J 0
(2700 1150);
DISPLAY 0.680851 (2700 1150);
PAINT MONO (2700 1150);
DISPLAY INVISIBLE (2700 1150);
FORCEPROP 2 LAST SEC_TYPE 0603V
J 0
(2700 1150);
DISPLAY 1.021277 (2700 1150);
PAINT ORANGE (2700 1150);
DISPLAY INVISIBLE (2700 1150);
FORCEPROP 2 LAST CDS_SEC 1
J 0
(2700 1100);
PAINT ORANGE (2700 1100);
DISPLAY INVISIBLE (2700 1100);
FORCEPROP 2 LAST CDS_LOCATION C5L15
J 0
(2700 1050);
DISPLAY 0.617021 (2700 1050);
PAINT AQUA (2700 1050);
DISPLAY INVISIBLE (2700 1050);
FORCEADD CAP_A..1
(3000 950);
FORCEPROP 1 LASTPIN (3000 850) $PN 2
J 0
(3010 830);
DISPLAY 0.617021 (3010 830);
PAINT ORANGE (3010 830);
FORCEPROP 1 LASTPIN (3000 1050) $PN 1
J 0
(3010 1030);
DISPLAY 0.617021 (3010 1030);
PAINT ORANGE (3010 1030);
FORCEPROP 1 LAST MATERIAL X5R
J 0
(3050 850);
DISPLAY 0.617021 (3050 850);
PAINT SKYBLUE (3050 850);
FORCEPROP 1 LAST VOLTAGE 4V
J 0
(3050 950);
DISPLAY 0.617021 (3050 950);
PAINT SKYBLUE (3050 950);
FORCEPROP 1 LAST PACK_TYPE 0603V
J 0
(3050 750);
DISPLAY 0.617021 (3050 750);
PAINT SKYBLUE (3050 750);
FORCEPROP 1 LAST TOLERANCE 20%
J 0
(3050 900);
DISPLAY 0.617021 (3050 900);
PAINT SKYBLUE (3050 900);
FORCEPROP 1 LAST VALUE 47UF
J 0
(3050 1000);
DISPLAY 0.617021 (3050 1000);
PAINT SKYBLUE (3050 1000);
FORCEPROP 1 LAST PART_NUMBER 602433-106
J 0
(3050 800);
DISPLAY 0.617021 (3050 800);
PAINT BLUE (3050 800);
FORCEPROP 1 LAST LOCATION C5A5
J 0
(3050 1050);
DISPLAY 0.617021 (3050 1050);
PAINT AQUA (3050 1050);
FORCEPROP 2 LAST CDS_LIB dev_discrete
J 0
(3000 950);
PAINT ORANGE (3000 950);
DISPLAY INVISIBLE (3000 950);
FORCEPROP 2 LAST SEC 1
J 0
(3050 1150);
DISPLAY 0.680851 (3050 1150);
PAINT MONO (3050 1150);
DISPLAY INVISIBLE (3050 1150);
FORCEPROP 2 LAST SEC_TYPE 0603V
J 0
(3050 1150);
DISPLAY 1.021277 (3050 1150);
PAINT ORANGE (3050 1150);
DISPLAY INVISIBLE (3050 1150);
FORCEPROP 2 LAST CDS_SEC 1
J 0
(3050 1100);
PAINT ORANGE (3050 1100);
DISPLAY INVISIBLE (3050 1100);
FORCEPROP 2 LAST CDS_LOCATION C5A5
J 0
(3050 1050);
DISPLAY 0.617021 (3050 1050);
PAINT AQUA (3050 1050);
DISPLAY INVISIBLE (3050 1050);
FORCEPROP 1 LAST PATH I193
J 0
(3050 1100);
DISPLAY 0.978723 (3050 1100);
PAINT WHITE (3050 1100);
DISPLAY INVISIBLE (3050 1100);
FORCEADD CAP_A..1
(3400 950);
FORCEPROP 1 LAST TOLERANCE 20%
J 0
(3450 900);
DISPLAY 0.617021 (3450 900);
PAINT SKYBLUE (3450 900);
FORCEPROP 1 LAST VOLTAGE 4V
J 0
(3450 950);
DISPLAY 0.617021 (3450 950);
PAINT SKYBLUE (3450 950);
FORCEPROP 1 LAST MATERIAL X5R
J 0
(3450 850);
DISPLAY 0.617021 (3450 850);
PAINT SKYBLUE (3450 850);
FORCEPROP 1 LASTPIN (3400 850) $PN 2
J 0
(3410 830);
DISPLAY 0.617021 (3410 830);
PAINT ORANGE (3410 830);
FORCEPROP 1 LAST PACK_TYPE 0603V
J 0
(3450 750);
DISPLAY 0.617021 (3450 750);
PAINT SKYBLUE (3450 750);
FORCEPROP 1 LAST PART_NUMBER 602433-106
J 0
(3450 800);
DISPLAY 0.617021 (3450 800);
PAINT BLUE (3450 800);
FORCEPROP 1 LAST VALUE 47UF
J 0
(3450 1000);
DISPLAY 0.617021 (3450 1000);
PAINT SKYBLUE (3450 1000);
FORCEPROP 1 LASTPIN (3400 1050) $PN 1
J 0
(3410 1030);
DISPLAY 0.617021 (3410 1030);
PAINT ORANGE (3410 1030);
FORCEPROP 1 LAST LOCATION C5B1
J 0
(3450 1050);
DISPLAY 0.617021 (3450 1050);
PAINT AQUA (3450 1050);
FORCEPROP 2 LAST CDS_LIB dev_discrete
J 0
(3400 950);
PAINT ORANGE (3400 950);
DISPLAY INVISIBLE (3400 950);
FORCEPROP 1 LAST PATH I194
J 0
(3450 1100);
DISPLAY 0.978723 (3450 1100);
PAINT WHITE (3450 1100);
DISPLAY INVISIBLE (3450 1100);
FORCEPROP 2 LAST SEC 1
J 0
(3450 1150);
DISPLAY 0.680851 (3450 1150);
PAINT MONO (3450 1150);
DISPLAY INVISIBLE (3450 1150);
FORCEPROP 2 LAST SEC_TYPE 0603V
J 0
(3450 1150);
DISPLAY 1.021277 (3450 1150);
PAINT ORANGE (3450 1150);
DISPLAY INVISIBLE (3450 1150);
FORCEPROP 2 LAST CDS_SEC 1
J 0
(3450 1100);
PAINT ORANGE (3450 1100);
DISPLAY INVISIBLE (3450 1100);
FORCEPROP 2 LAST CDS_LOCATION C5B1
J 0
(3450 1050);
DISPLAY 0.617021 (3450 1050);
PAINT AQUA (3450 1050);
DISPLAY INVISIBLE (3450 1050);
FORCEADD CAP_A..1
(4125 1675);
FORCEPROP 1 LAST PACK_TYPE 0603V
J 0
(4175 1475);
DISPLAY 0.617021 (4175 1475);
PAINT SKYBLUE (4175 1475);
FORCEPROP 1 LAST PART_NUMBER 602433-106
J 0
(4175 1525);
DISPLAY 0.617021 (4175 1525);
PAINT BLUE (4175 1525);
FORCEPROP 1 LAST VALUE 47UF
J 0
(4175 1725);
DISPLAY 0.617021 (4175 1725);
PAINT SKYBLUE (4175 1725);
FORCEPROP 1 LAST TOLERANCE 20%
J 0
(4175 1625);
DISPLAY 0.617021 (4175 1625);
PAINT SKYBLUE (4175 1625);
FORCEPROP 1 LAST VOLTAGE 4V
J 0
(4175 1675);
DISPLAY 0.617021 (4175 1675);
PAINT SKYBLUE (4175 1675);
FORCEPROP 1 LAST MATERIAL X5R
J 0
(4175 1575);
DISPLAY 0.617021 (4175 1575);
PAINT SKYBLUE (4175 1575);
FORCEPROP 1 LASTPIN (4125 1775) $PN 1
J 0
(4135 1755);
DISPLAY 0.617021 (4135 1755);
PAINT ORANGE (4135 1755);
FORCEPROP 1 LASTPIN (4125 1575) $PN 2
J 0
(4135 1555);
DISPLAY 0.617021 (4135 1555);
PAINT ORANGE (4135 1555);
FORCEPROP 1 LAST LOCATION C5M9
J 0
(4175 1775);
DISPLAY 0.617021 (4175 1775);
PAINT AQUA (4175 1775);
FORCEPROP 2 LAST CDS_LIB dev_discrete
J 0
(4125 1675);
PAINT ORANGE (4125 1675);
DISPLAY INVISIBLE (4125 1675);
FORCEPROP 2 LAST CDS_LOCATION C5M9
J 0
(4175 1775);
DISPLAY 0.617021 (4175 1775);
PAINT AQUA (4175 1775);
DISPLAY INVISIBLE (4175 1775);
FORCEPROP 2 LAST CDS_SEC 1
J 0
(4175 1825);
PAINT ORANGE (4175 1825);
DISPLAY INVISIBLE (4175 1825);
FORCEPROP 2 LAST SEC_TYPE 0603V
J 0
(4175 1875);
DISPLAY 1.021277 (4175 1875);
PAINT ORANGE (4175 1875);
DISPLAY INVISIBLE (4175 1875);
FORCEPROP 2 LAST SEC 1
J 0
(4175 1875);
DISPLAY 0.680851 (4175 1875);
PAINT MONO (4175 1875);
DISPLAY INVISIBLE (4175 1875);
FORCEPROP 1 LAST PATH I195
J 0
(4175 1825);
DISPLAY 0.978723 (4175 1825);
PAINT WHITE (4175 1825);
DISPLAY INVISIBLE (4175 1825);
FORCEADD CAP_A..1
(3775 1675);
FORCEPROP 1 LAST PACK_TYPE 0603V
J 0
(3825 1475);
DISPLAY 0.617021 (3825 1475);
PAINT SKYBLUE (3825 1475);
FORCEPROP 1 LASTPIN (3775 1775) $PN 1
J 0
(3785 1755);
DISPLAY 0.617021 (3785 1755);
PAINT ORANGE (3785 1755);
FORCEPROP 1 LASTPIN (3775 1575) $PN 2
J 0
(3785 1555);
DISPLAY 0.617021 (3785 1555);
PAINT ORANGE (3785 1555);
FORCEPROP 1 LAST MATERIAL X5R
J 0
(3825 1575);
DISPLAY 0.617021 (3825 1575);
PAINT SKYBLUE (3825 1575);
FORCEPROP 1 LAST VOLTAGE 4V
J 0
(3825 1675);
DISPLAY 0.617021 (3825 1675);
PAINT SKYBLUE (3825 1675);
FORCEPROP 1 LAST TOLERANCE 20%
J 0
(3825 1625);
DISPLAY 0.617021 (3825 1625);
PAINT SKYBLUE (3825 1625);
FORCEPROP 1 LAST VALUE 47UF
J 0
(3825 1725);
DISPLAY 0.617021 (3825 1725);
PAINT SKYBLUE (3825 1725);
FORCEPROP 1 LAST LOCATION C4M5
J 0
(3825 1775);
DISPLAY 0.617021 (3825 1775);
PAINT AQUA (3825 1775);
FORCEPROP 1 LAST PART_NUMBER 602433-106
J 0
(3825 1525);
DISPLAY 0.617021 (3825 1525);
PAINT BLUE (3825 1525);
FORCEPROP 2 LAST CDS_LIB dev_discrete
J 0
(3775 1675);
PAINT ORANGE (3775 1675);
DISPLAY INVISIBLE (3775 1675);
FORCEPROP 2 LAST CDS_LOCATION C4M5
J 0
(3825 1775);
DISPLAY 0.617021 (3825 1775);
PAINT AQUA (3825 1775);
DISPLAY INVISIBLE (3825 1775);
FORCEPROP 2 LAST CDS_SEC 1
J 0
(3825 1825);
PAINT ORANGE (3825 1825);
DISPLAY INVISIBLE (3825 1825);
FORCEPROP 2 LAST SEC_TYPE 0603V
J 0
(3825 1875);
DISPLAY 1.021277 (3825 1875);
PAINT ORANGE (3825 1875);
DISPLAY INVISIBLE (3825 1875);
FORCEPROP 1 LAST PATH I196
J 0
(3825 1825);
DISPLAY 0.978723 (3825 1825);
PAINT WHITE (3825 1825);
DISPLAY INVISIBLE (3825 1825);
FORCEPROP 2 LAST SEC 1
J 0
(3825 1875);
DISPLAY 0.680851 (3825 1875);
PAINT MONO (3825 1875);
DISPLAY INVISIBLE (3825 1875);
FORCEADD CAP_A..1
(2675 1675);
FORCEPROP 1 LAST PACK_TYPE 0603V
J 0
(2725 1475);
DISPLAY 0.617021 (2725 1475);
PAINT SKYBLUE (2725 1475);
FORCEPROP 1 LAST PART_NUMBER 602433-106
J 0
(2725 1525);
DISPLAY 0.617021 (2725 1525);
PAINT BLUE (2725 1525);
FORCEPROP 1 LAST VOLTAGE 4V
J 0
(2725 1675);
DISPLAY 0.617021 (2725 1675);
PAINT SKYBLUE (2725 1675);
FORCEPROP 1 LAST MATERIAL X5R
J 0
(2725 1575);
DISPLAY 0.617021 (2725 1575);
PAINT SKYBLUE (2725 1575);
FORCEPROP 1 LASTPIN (2675 1775) $PN 1
J 0
(2685 1755);
DISPLAY 0.617021 (2685 1755);
PAINT ORANGE (2685 1755);
FORCEPROP 1 LASTPIN (2675 1575) $PN 2
J 0
(2685 1555);
DISPLAY 0.617021 (2685 1555);
PAINT ORANGE (2685 1555);
FORCEPROP 1 LAST TOLERANCE 20%
J 0
(2725 1625);
DISPLAY 0.617021 (2725 1625);
PAINT SKYBLUE (2725 1625);
FORCEPROP 1 LAST VALUE 47UF
J 0
(2725 1725);
DISPLAY 0.617021 (2725 1725);
PAINT SKYBLUE (2725 1725);
FORCEPROP 1 LAST LOCATION C5B2
J 0
(2725 1775);
DISPLAY 0.617021 (2725 1775);
PAINT AQUA (2725 1775);
FORCEPROP 2 LAST CDS_LIB dev_discrete
J 0
(2675 1675);
PAINT ORANGE (2675 1675);
DISPLAY INVISIBLE (2675 1675);
FORCEPROP 2 LAST CDS_LOCATION C5B2
J 0
(2725 1775);
DISPLAY 0.617021 (2725 1775);
PAINT AQUA (2725 1775);
DISPLAY INVISIBLE (2725 1775);
FORCEPROP 2 LAST CDS_SEC 1
J 0
(2725 1825);
PAINT ORANGE (2725 1825);
DISPLAY INVISIBLE (2725 1825);
FORCEPROP 2 LAST SEC_TYPE 0603V
J 0
(2725 1875);
DISPLAY 1.021277 (2725 1875);
PAINT ORANGE (2725 1875);
DISPLAY INVISIBLE (2725 1875);
FORCEPROP 2 LAST SEC 1
J 0
(2725 1875);
DISPLAY 0.680851 (2725 1875);
PAINT MONO (2725 1875);
DISPLAY INVISIBLE (2725 1875);
FORCEPROP 1 LAST PATH I197
J 0
(2725 1825);
DISPLAY 0.978723 (2725 1825);
PAINT WHITE (2725 1825);
DISPLAY INVISIBLE (2725 1825);
FORCEADD CAP_A..1
(3025 1675);
FORCEPROP 1 LASTPIN (3025 1775) $PN 1
J 0
(3035 1755);
DISPLAY 0.617021 (3035 1755);
PAINT ORANGE (3035 1755);
FORCEPROP 1 LASTPIN (3025 1575) $PN 2
J 0
(3035 1555);
DISPLAY 0.617021 (3035 1555);
PAINT ORANGE (3035 1555);
FORCEPROP 1 LAST PACK_TYPE 0603V
J 0
(3075 1475);
DISPLAY 0.617021 (3075 1475);
PAINT SKYBLUE (3075 1475);
FORCEPROP 1 LAST PART_NUMBER 602433-106
J 0
(3075 1525);
DISPLAY 0.617021 (3075 1525);
PAINT BLUE (3075 1525);
FORCEPROP 1 LAST MATERIAL X5R
J 0
(3075 1575);
DISPLAY 0.617021 (3075 1575);
PAINT SKYBLUE (3075 1575);
FORCEPROP 1 LAST VOLTAGE 4V
J 0
(3075 1675);
DISPLAY 0.617021 (3075 1675);
PAINT SKYBLUE (3075 1675);
FORCEPROP 1 LAST TOLERANCE 20%
J 0
(3075 1625);
DISPLAY 0.617021 (3075 1625);
PAINT SKYBLUE (3075 1625);
FORCEPROP 1 LAST VALUE 47UF
J 0
(3075 1725);
DISPLAY 0.617021 (3075 1725);
PAINT SKYBLUE (3075 1725);
FORCEPROP 1 LAST LOCATION C5M10
J 0
(3075 1775);
DISPLAY 0.617021 (3075 1775);
PAINT AQUA (3075 1775);
FORCEPROP 2 LAST CDS_LIB dev_discrete
J 0
(3025 1675);
PAINT ORANGE (3025 1675);
DISPLAY INVISIBLE (3025 1675);
FORCEPROP 1 LAST PATH I198
J 0
(3075 1825);
DISPLAY 0.978723 (3075 1825);
PAINT WHITE (3075 1825);
DISPLAY INVISIBLE (3075 1825);
FORCEPROP 2 LAST SEC 1
J 0
(3075 1875);
DISPLAY 0.680851 (3075 1875);
PAINT MONO (3075 1875);
DISPLAY INVISIBLE (3075 1875);
FORCEPROP 2 LAST SEC_TYPE 0603V
J 0
(3075 1875);
DISPLAY 1.021277 (3075 1875);
PAINT ORANGE (3075 1875);
DISPLAY INVISIBLE (3075 1875);
FORCEPROP 2 LAST CDS_SEC 1
J 0
(3075 1825);
PAINT ORANGE (3075 1825);
DISPLAY INVISIBLE (3075 1825);
FORCEPROP 2 LAST CDS_LOCATION C5M10
J 0
(3075 1775);
DISPLAY 0.617021 (3075 1775);
PAINT AQUA (3075 1775);
DISPLAY INVISIBLE (3075 1775);
FORCEADD CAP_A..1
(3425 1675);
FORCEPROP 1 LAST TOLERANCE 20%
J 0
(3475 1625);
DISPLAY 0.617021 (3475 1625);
PAINT SKYBLUE (3475 1625);
FORCEPROP 1 LAST VOLTAGE 4V
J 0
(3475 1675);
DISPLAY 0.617021 (3475 1675);
PAINT SKYBLUE (3475 1675);
FORCEPROP 1 LAST MATERIAL X5R
J 0
(3475 1575);
DISPLAY 0.617021 (3475 1575);
PAINT SKYBLUE (3475 1575);
FORCEPROP 1 LASTPIN (3425 1775) $PN 1
J 0
(3435 1755);
DISPLAY 0.617021 (3435 1755);
PAINT ORANGE (3435 1755);
FORCEPROP 1 LASTPIN (3425 1575) $PN 2
J 0
(3435 1555);
DISPLAY 0.617021 (3435 1555);
PAINT ORANGE (3435 1555);
FORCEPROP 1 LAST PACK_TYPE 0603V
J 0
(3475 1475);
DISPLAY 0.617021 (3475 1475);
PAINT SKYBLUE (3475 1475);
FORCEPROP 1 LAST VALUE 47UF
J 0
(3475 1725);
DISPLAY 0.617021 (3475 1725);
PAINT SKYBLUE (3475 1725);
FORCEPROP 1 LAST PART_NUMBER 602433-106
J 0
(3475 1525);
DISPLAY 0.617021 (3475 1525);
PAINT BLUE (3475 1525);
FORCEPROP 1 LAST LOCATION C5M3
J 0
(3475 1775);
DISPLAY 0.617021 (3475 1775);
PAINT AQUA (3475 1775);
FORCEPROP 2 LAST CDS_LIB dev_discrete
J 0
(3425 1675);
PAINT ORANGE (3425 1675);
DISPLAY INVISIBLE (3425 1675);
FORCEPROP 2 LAST CDS_LOCATION C5M3
J 0
(3475 1775);
DISPLAY 0.617021 (3475 1775);
PAINT AQUA (3475 1775);
DISPLAY INVISIBLE (3475 1775);
FORCEPROP 1 LAST PATH I199
J 0
(3475 1825);
DISPLAY 0.978723 (3475 1825);
PAINT WHITE (3475 1825);
DISPLAY INVISIBLE (3475 1825);
FORCEPROP 2 LAST SEC 1
J 0
(3475 1875);
DISPLAY 0.680851 (3475 1875);
PAINT MONO (3475 1875);
DISPLAY INVISIBLE (3475 1875);
FORCEPROP 2 LAST SEC_TYPE 0603V
J 0
(3475 1875);
DISPLAY 1.021277 (3475 1875);
PAINT ORANGE (3475 1875);
DISPLAY INVISIBLE (3475 1875);
FORCEPROP 2 LAST CDS_SEC 1
J 0
(3475 1825);
PAINT ORANGE (3475 1825);
DISPLAY INVISIBLE (3475 1825);
FORCEADD CAP_A..1
(4525 1675);
FORCEPROP 1 LASTPIN (4525 1575) $PN 2
J 0
(4535 1555);
DISPLAY 0.617021 (4535 1555);
PAINT ORANGE (4535 1555);
FORCEPROP 1 LASTPIN (4525 1775) $PN 1
J 0
(4535 1755);
DISPLAY 0.617021 (4535 1755);
PAINT ORANGE (4535 1755);
FORCEPROP 1 LAST MATERIAL X5R
J 0
(4575 1575);
DISPLAY 0.617021 (4575 1575);
PAINT SKYBLUE (4575 1575);
FORCEPROP 1 LAST VOLTAGE 4V
J 0
(4575 1675);
DISPLAY 0.617021 (4575 1675);
PAINT SKYBLUE (4575 1675);
FORCEPROP 1 LAST PACK_TYPE 0603V
J 0
(4575 1475);
DISPLAY 0.617021 (4575 1475);
PAINT SKYBLUE (4575 1475);
FORCEPROP 1 LAST TOLERANCE 20%
J 0
(4575 1625);
DISPLAY 0.617021 (4575 1625);
PAINT SKYBLUE (4575 1625);
FORCEPROP 1 LAST VALUE 47UF
J 0
(4575 1725);
DISPLAY 0.617021 (4575 1725);
PAINT SKYBLUE (4575 1725);
FORCEPROP 1 LAST PART_NUMBER 602433-106
J 0
(4575 1525);
DISPLAY 0.617021 (4575 1525);
PAINT BLUE (4575 1525);
FORCEPROP 1 LAST LOCATION C5M11
J 0
(4575 1775);
DISPLAY 0.617021 (4575 1775);
PAINT AQUA (4575 1775);
FORCEPROP 2 LAST CDS_LIB dev_discrete
J 0
(4525 1675);
PAINT ORANGE (4525 1675);
DISPLAY INVISIBLE (4525 1675);
FORCEPROP 2 LAST CDS_LOCATION C5M11
J 0
(4575 1775);
DISPLAY 0.617021 (4575 1775);
PAINT AQUA (4575 1775);
DISPLAY INVISIBLE (4575 1775);
FORCEPROP 2 LAST SEC_TYPE 0603V
J 0
(4575 1875);
DISPLAY 1.021277 (4575 1875);
PAINT ORANGE (4575 1875);
DISPLAY INVISIBLE (4575 1875);
FORCEPROP 2 LAST CDS_SEC 1
J 0
(4575 1825);
PAINT ORANGE (4575 1825);
DISPLAY INVISIBLE (4575 1825);
FORCEPROP 1 LAST PATH I200
J 0
(4575 1825);
DISPLAY 0.978723 (4575 1825);
PAINT WHITE (4575 1825);
DISPLAY INVISIBLE (4575 1825);
FORCEPROP 2 LAST SEC 1
J 0
(4575 1875);
DISPLAY 0.680851 (4575 1875);
PAINT MONO (4575 1875);
DISPLAY INVISIBLE (4575 1875);
FORCEADD PVDDQ_DEF..1
(-1475 3175);
FORCEPROP 3 LASTPIN (-1475 3125) SIG_NAME PVDDQ_DEF\g
J 0
(-1465 3135);
DISPLAY 0.659574 (-1465 3135);
PAINT MONO (-1465 3135);
DISPLAY INVISIBLE (-1465 3135);
FORCEPROP 1 LAST BODY_TYPE PLUMBING
J 0
(-1520 3132);
DISPLAY 0.340426 (-1520 3132);
PAINT GREEN (-1520 3132);
DISPLAY INVISIBLE (-1520 3132);
FORCEPROP 1 LAST VOLTAGE 1.2V
J 0
(-1520 3132);
DISPLAY 0.340426 (-1520 3132);
PAINT SKYBLUE (-1520 3132);
DISPLAY INVISIBLE (-1520 3132);
FORCEPROP 1 LAST PATH I201
J 0
(-1425 3200);
DISPLAY 0.872340 (-1425 3200);
PAINT AQUA (-1425 3200);
DISPLAY INVISIBLE (-1425 3200);
FORCEPROP 2 LAST CDS_LIB mstr_symbols
J 0
(-1475 3175);
PAINT ORANGE (-1475 3175);
DISPLAY INVISIBLE (-1475 3175);
FORCEPROP 2 LAST BOM_COST MEM_VRD_PVPP_DEF
J 0
(-1425 3275);
PAINT MONO (-1425 3275);
DISPLAY INVISIBLE (-1425 3275);
FORCEPROP 1 LAST HDL_POWER PVDDQ_DEF
J 1
(-1475 3225);
DISPLAY 0.872340 (-1475 3225);
PAINT GREEN (-1475 3225);
DISPLAY INVISIBLE (-1475 3225);
FORCEPROP 2 LAST ROOM VDDQ_DEF_PWR_VR
J 0
(-1250 3275);
PAINT ORANGE (-1250 3275);
DISPLAY INVISIBLE (-1250 3275);
FORCEADD GND..1
(-1875 2525);
FORCEPROP 3 LASTPIN (-1875 2575) SIG_NAME GND\g
J 0
(-1865 2585);
DISPLAY 0.659574 (-1865 2585);
PAINT MONO (-1865 2585);
DISPLAY INVISIBLE (-1865 2585);
FORCEPROP 2 LAST ROOM VDDQ_ABC_PWR_VR
J 0
(-2425 2600);
PAINT ORANGE (-2425 2600);
DISPLAY INVISIBLE (-2425 2600);
FORCEPROP 2 LAST BOM_COST MEM_VRD_PVDDQ_CD
J 0
(-2200 2600);
PAINT MONO (-2200 2600);
DISPLAY INVISIBLE (-2200 2600);
FORCEPROP 1 LAST BODY_TYPE PLUMBING
J 0
(-1920 2482);
DISPLAY 0.340426 (-1920 2482);
PAINT GREEN (-1920 2482);
DISPLAY INVISIBLE (-1920 2482);
FORCEPROP 1 LAST SIZE 1B
J 0
(-1800 2475);
DISPLAY 0.893617 (-1800 2475);
PAINT GREEN (-1800 2475);
DISPLAY INVISIBLE (-1800 2475);
FORCEPROP 1 LAST PATH I202
J 0
(-1800 2525);
DISPLAY 0.872340 (-1800 2525);
PAINT AQUA (-1800 2525);
DISPLAY INVISIBLE (-1800 2525);
FORCEPROP 2 LAST CDS_LIB mstr_symbols
J 0
(-1875 2525);
PAINT ORANGE (-1875 2525);
DISPLAY INVISIBLE (-1875 2525);
FORCEPROP 1 LAST VOLTAGE 0
J 0
(-1875 2525);
PAINT SKYBLUE (-1875 2525);
DISPLAY INVISIBLE (-1875 2525);
FORCEPROP 1 LAST HDL_POWER GND
J 0
(-1875 2675);
DISPLAY 0.893617 (-1875 2675);
PAINT GREEN (-1875 2675);
DISPLAY INVISIBLE (-1875 2675);
FORCEADD CAP_A..1
(2225 100);
FORCEPROP 1 LAST PACK_TYPE 0603V
J 0
(2275 -100);
DISPLAY 0.617021 (2275 -100);
PAINT SKYBLUE (2275 -100);
FORCEPROP 1 LAST PART_NUMBER E15431-004
J 0
(2275 -50);
DISPLAY 0.617021 (2275 -50);
PAINT BLUE (2275 -50);
FORCEPROP 1 LAST MATERIAL X6S
J 0
(2275 0);
DISPLAY 0.617021 (2275 0);
PAINT SKYBLUE (2275 0);
FORCEPROP 1 LAST VOLTAGE 4V
J 0
(2275 100);
DISPLAY 0.617021 (2275 100);
PAINT SKYBLUE (2275 100);
FORCEPROP 1 LAST TOLERANCE 20%
J 0
(2275 50);
DISPLAY 0.617021 (2275 50);
PAINT SKYBLUE (2275 50);
FORCEPROP 1 LAST VALUE 22.0UF
J 0
(2275 150);
DISPLAY 0.617021 (2275 150);
PAINT SKYBLUE (2275 150);
FORCEPROP 1 LAST LOCATION C5A19
J 0
(2275 200);
DISPLAY 0.617021 (2275 200);
PAINT AQUA (2275 200);
FORCEPROP 1 LASTPIN (2225 0) $PN 2
J 0
(2235 -20);
DISPLAY 0.787234 (2235 -20);
PAINT ORANGE (2235 -20);
DISPLAY INVISIBLE (2235 -20);
FORCEPROP 1 LASTPIN (2225 200) $PN 1
J 0
(2235 180);
DISPLAY 0.787234 (2235 180);
PAINT ORANGE (2235 180);
DISPLAY INVISIBLE (2235 180);
FORCEPROP 2 LAST CDS_LOCATION C5A19
J 0
(2275 200);
DISPLAY 0.617021 (2275 200);
PAINT AQUA (2275 200);
DISPLAY INVISIBLE (2275 200);
FORCEPROP 2 LAST CDS_LIB dev_discrete
J 0
(2225 100);
PAINT ORANGE (2225 100);
DISPLAY INVISIBLE (2225 100);
FORCEPROP 1 LAST PATH I203
J 0
(2275 250);
DISPLAY 0.978723 (2275 250);
PAINT WHITE (2275 250);
DISPLAY INVISIBLE (2275 250);
FORCEPROP 0 LAST ROOM PVDDQ_DEF
J 0
(2275 300);
DISPLAY 1.021277 (2275 300);
PAINT ORANGE (2275 300);
DISPLAY INVISIBLE (2275 300);
FORCEPROP 2 LAST CDS_SEC 1
J 0
(2275 300);
PAINT MONO (2275 300);
DISPLAY INVISIBLE (2275 300);
FORCEPROP 2 LAST $SEC 1
J 0
(2275 300);
PAINT MONO (2275 300);
DISPLAY INVISIBLE (2275 300);
FORCEADD CAP_A..1
(1950 100);
FORCEPROP 1 LAST PACK_TYPE 0603V
J 0
(2000 -100);
DISPLAY 0.617021 (2000 -100);
PAINT SKYBLUE (2000 -100);
FORCEPROP 1 LAST PART_NUMBER E15431-004
J 0
(2000 -50);
DISPLAY 0.617021 (2000 -50);
PAINT BLUE (2000 -50);
FORCEPROP 1 LAST MATERIAL X6S
J 0
(2000 0);
DISPLAY 0.617021 (2000 0);
PAINT SKYBLUE (2000 0);
FORCEPROP 1 LAST VOLTAGE 4V
J 0
(2000 100);
DISPLAY 0.617021 (2000 100);
PAINT SKYBLUE (2000 100);
FORCEPROP 1 LAST TOLERANCE 20%
J 0
(2000 50);
DISPLAY 0.617021 (2000 50);
PAINT SKYBLUE (2000 50);
FORCEPROP 1 LAST VALUE 22.0UF
J 0
(2000 150);
DISPLAY 0.617021 (2000 150);
PAINT SKYBLUE (2000 150);
FORCEPROP 1 LAST LOCATION C5A18
J 0
(2000 200);
DISPLAY 0.617021 (2000 200);
PAINT AQUA (2000 200);
FORCEPROP 1 LASTPIN (1950 0) $PN 2
J 0
(1960 -20);
DISPLAY 0.787234 (1960 -20);
PAINT ORANGE (1960 -20);
DISPLAY INVISIBLE (1960 -20);
FORCEPROP 1 LASTPIN (1950 200) $PN 1
J 0
(1960 180);
DISPLAY 0.787234 (1960 180);
PAINT ORANGE (1960 180);
DISPLAY INVISIBLE (1960 180);
FORCEPROP 2 LAST CDS_LOCATION C5A18
J 0
(2000 200);
DISPLAY 0.617021 (2000 200);
PAINT AQUA (2000 200);
DISPLAY INVISIBLE (2000 200);
FORCEPROP 2 LAST CDS_LIB dev_discrete
J 0
(1950 100);
PAINT ORANGE (1950 100);
DISPLAY INVISIBLE (1950 100);
FORCEPROP 1 LAST PATH I204
J 0
(2000 250);
DISPLAY 0.978723 (2000 250);
PAINT WHITE (2000 250);
DISPLAY INVISIBLE (2000 250);
FORCEPROP 0 LAST ROOM PVDDQ_DEF
J 0
(2000 300);
DISPLAY 1.021277 (2000 300);
PAINT ORANGE (2000 300);
DISPLAY INVISIBLE (2000 300);
FORCEPROP 2 LAST CDS_SEC 1
J 0
(2000 300);
PAINT MONO (2000 300);
DISPLAY INVISIBLE (2000 300);
FORCEPROP 2 LAST $SEC 1
J 0
(2000 300);
PAINT MONO (2000 300);
DISPLAY INVISIBLE (2000 300);
FORCEADD CAP_A..1
(1650 100);
FORCEPROP 1 LAST PART_NUMBER E15431-004
J 0
(1700 -50);
DISPLAY 0.617021 (1700 -50);
PAINT BLUE (1700 -50);
FORCEPROP 1 LAST PACK_TYPE 0603V
J 0
(1700 -100);
DISPLAY 0.617021 (1700 -100);
PAINT SKYBLUE (1700 -100);
FORCEPROP 1 LAST MATERIAL X6S
J 0
(1700 0);
DISPLAY 0.617021 (1700 0);
PAINT SKYBLUE (1700 0);
FORCEPROP 1 LAST VOLTAGE 4V
J 0
(1700 100);
DISPLAY 0.617021 (1700 100);
PAINT SKYBLUE (1700 100);
FORCEPROP 1 LAST TOLERANCE 20%
J 0
(1700 50);
DISPLAY 0.617021 (1700 50);
PAINT SKYBLUE (1700 50);
FORCEPROP 1 LAST VALUE 22.0UF
J 0
(1700 150);
DISPLAY 0.617021 (1700 150);
PAINT SKYBLUE (1700 150);
FORCEPROP 1 LAST LOCATION C5A17
J 0
(1700 200);
DISPLAY 0.617021 (1700 200);
PAINT AQUA (1700 200);
FORCEPROP 1 LASTPIN (1650 0) $PN 2
J 0
(1660 -20);
DISPLAY 0.787234 (1660 -20);
PAINT ORANGE (1660 -20);
DISPLAY INVISIBLE (1660 -20);
FORCEPROP 2 LAST CDS_LIB dev_discrete
J 0
(1650 100);
PAINT ORANGE (1650 100);
DISPLAY INVISIBLE (1650 100);
FORCEPROP 1 LASTPIN (1650 200) $PN 1
J 0
(1660 180);
DISPLAY 0.787234 (1660 180);
PAINT ORANGE (1660 180);
DISPLAY INVISIBLE (1660 180);
FORCEPROP 2 LAST CDS_LOCATION C5A17
J 0
(1700 200);
DISPLAY 0.617021 (1700 200);
PAINT AQUA (1700 200);
DISPLAY INVISIBLE (1700 200);
FORCEPROP 1 LAST PATH I205
J 0
(1700 250);
DISPLAY 0.978723 (1700 250);
PAINT WHITE (1700 250);
DISPLAY INVISIBLE (1700 250);
FORCEPROP 0 LAST ROOM PVDDQ_DEF
J 0
(1700 300);
DISPLAY 1.021277 (1700 300);
PAINT ORANGE (1700 300);
DISPLAY INVISIBLE (1700 300);
FORCEPROP 2 LAST CDS_SEC 1
J 0
(1700 300);
PAINT MONO (1700 300);
DISPLAY INVISIBLE (1700 300);
FORCEPROP 2 LAST $SEC 1
J 0
(1700 300);
PAINT MONO (1700 300);
DISPLAY INVISIBLE (1700 300);
FORCEADD CAP_A..1
(1350 100);
FORCEPROP 1 LAST PACK_TYPE 0603V
J 0
(1400 -100);
DISPLAY 0.617021 (1400 -100);
PAINT SKYBLUE (1400 -100);
FORCEPROP 1 LAST PART_NUMBER E15431-004
J 0
(1400 -50);
DISPLAY 0.617021 (1400 -50);
PAINT BLUE (1400 -50);
FORCEPROP 1 LASTPIN (1350 0) $PN 2
J 0
(1360 -20);
DISPLAY 0.617021 (1360 -20);
PAINT ORANGE (1360 -20);
FORCEPROP 1 LAST MATERIAL X6S
J 0
(1400 0);
DISPLAY 0.617021 (1400 0);
PAINT SKYBLUE (1400 0);
FORCEPROP 1 LASTPIN (1350 200) $PN 1
J 0
(1360 180);
DISPLAY 0.617021 (1360 180);
PAINT ORANGE (1360 180);
FORCEPROP 1 LAST VOLTAGE 4V
J 0
(1400 100);
DISPLAY 0.617021 (1400 100);
PAINT SKYBLUE (1400 100);
FORCEPROP 1 LAST TOLERANCE 20%
J 0
(1400 50);
DISPLAY 0.617021 (1400 50);
PAINT SKYBLUE (1400 50);
FORCEPROP 1 LAST LOCATION C5A4
J 0
(1400 200);
DISPLAY 0.617021 (1400 200);
PAINT AQUA (1400 200);
FORCEPROP 1 LAST VALUE 22.0UF
J 0
(1400 150);
DISPLAY 0.617021 (1400 150);
PAINT SKYBLUE (1400 150);
FORCEPROP 2 LAST CDS_LIB dev_discrete
J 0
(1350 100);
PAINT ORANGE (1350 100);
DISPLAY INVISIBLE (1350 100);
FORCEPROP 2 LAST CDS_LOCATION C5A4
J 0
(1400 200);
DISPLAY 0.617021 (1400 200);
PAINT AQUA (1400 200);
DISPLAY INVISIBLE (1400 200);
FORCEPROP 2 LAST CDS_SEC 1
J 0
(1400 250);
PAINT ORANGE (1400 250);
DISPLAY INVISIBLE (1400 250);
FORCEPROP 1 LAST PATH I206
J 0
(1400 250);
DISPLAY 0.978723 (1400 250);
PAINT WHITE (1400 250);
DISPLAY INVISIBLE (1400 250);
FORCEPROP 0 LAST ROOM PVDDQ_DEF
J 0
(1400 300);
DISPLAY 1.021277 (1400 300);
PAINT ORANGE (1400 300);
DISPLAY INVISIBLE (1400 300);
FORCEPROP 2 LAST SEC_TYPE 0603V
J 0
(1400 300);
DISPLAY 1.021277 (1400 300);
PAINT ORANGE (1400 300);
DISPLAY INVISIBLE (1400 300);
FORCEPROP 2 LAST SEC 1
J 0
(1400 300);
DISPLAY 0.680851 (1400 300);
PAINT MONO (1400 300);
DISPLAY INVISIBLE (1400 300);
FORCEADD CAP_A..1
(1075 100);
FORCEPROP 1 LAST PACK_TYPE 0603V
J 0
(1125 -100);
DISPLAY 0.617021 (1125 -100);
PAINT SKYBLUE (1125 -100);
FORCEPROP 1 LAST PART_NUMBER E15431-004
J 0
(1125 -50);
DISPLAY 0.617021 (1125 -50);
PAINT BLUE (1125 -50);
FORCEPROP 1 LAST MATERIAL X6S
J 0
(1125 0);
DISPLAY 0.617021 (1125 0);
PAINT SKYBLUE (1125 0);
FORCEPROP 1 LAST VOLTAGE 4V
J 0
(1125 100);
DISPLAY 0.617021 (1125 100);
PAINT SKYBLUE (1125 100);
FORCEPROP 1 LAST TOLERANCE 20%
J 0
(1125 50);
DISPLAY 0.617021 (1125 50);
PAINT SKYBLUE (1125 50);
FORCEPROP 1 LAST LOCATION C5A16
J 0
(1125 200);
DISPLAY 0.617021 (1125 200);
PAINT AQUA (1125 200);
FORCEPROP 1 LAST VALUE 22.0UF
J 0
(1125 150);
DISPLAY 0.617021 (1125 150);
PAINT SKYBLUE (1125 150);
FORCEPROP 1 LASTPIN (1075 0) $PN 2
J 0
(1085 -20);
DISPLAY 0.787234 (1085 -20);
PAINT ORANGE (1085 -20);
DISPLAY INVISIBLE (1085 -20);
FORCEPROP 2 LAST CDS_LIB dev_discrete
J 0
(1075 100);
PAINT ORANGE (1075 100);
DISPLAY INVISIBLE (1075 100);
FORCEPROP 2 LAST CDS_LOCATION C5A16
J 0
(1125 200);
DISPLAY 0.617021 (1125 200);
PAINT AQUA (1125 200);
DISPLAY INVISIBLE (1125 200);
FORCEPROP 1 LASTPIN (1075 200) $PN 1
J 0
(1085 180);
DISPLAY 0.787234 (1085 180);
PAINT ORANGE (1085 180);
DISPLAY INVISIBLE (1085 180);
FORCEPROP 1 LAST PATH I207
J 0
(1125 250);
DISPLAY 0.978723 (1125 250);
PAINT WHITE (1125 250);
DISPLAY INVISIBLE (1125 250);
FORCEPROP 0 LAST ROOM PVDDQ_DEF
J 0
(1125 300);
DISPLAY 1.021277 (1125 300);
PAINT ORANGE (1125 300);
DISPLAY INVISIBLE (1125 300);
FORCEPROP 2 LAST CDS_SEC 1
J 0
(1125 300);
PAINT MONO (1125 300);
DISPLAY INVISIBLE (1125 300);
FORCEPROP 2 LAST $SEC 1
J 0
(1125 300);
PAINT MONO (1125 300);
DISPLAY INVISIBLE (1125 300);
FORCEADD CAP_A..1
(800 100);
FORCEPROP 1 LAST PACK_TYPE 0603V
J 0
(850 -100);
DISPLAY 0.617021 (850 -100);
PAINT SKYBLUE (850 -100);
FORCEPROP 1 LAST PART_NUMBER E15431-004
J 0
(850 -50);
DISPLAY 0.617021 (850 -50);
PAINT BLUE (850 -50);
FORCEPROP 1 LAST MATERIAL X6S
J 0
(850 0);
DISPLAY 0.617021 (850 0);
PAINT SKYBLUE (850 0);
FORCEPROP 1 LAST LOCATION C5A9
J 0
(850 200);
DISPLAY 0.617021 (850 200);
PAINT AQUA (850 200);
FORCEPROP 1 LAST TOLERANCE 20%
J 0
(850 50);
DISPLAY 0.617021 (850 50);
PAINT SKYBLUE (850 50);
FORCEPROP 1 LAST VOLTAGE 4V
J 0
(850 100);
DISPLAY 0.617021 (850 100);
PAINT SKYBLUE (850 100);
FORCEPROP 1 LAST VALUE 22.0UF
J 0
(850 150);
DISPLAY 0.617021 (850 150);
PAINT SKYBLUE (850 150);
FORCEPROP 1 LASTPIN (800 0) $PN 2
J 0
(810 -20);
DISPLAY 0.787234 (810 -20);
PAINT ORANGE (810 -20);
DISPLAY INVISIBLE (810 -20);
FORCEPROP 1 LASTPIN (800 200) $PN 1
J 0
(810 180);
DISPLAY 0.787234 (810 180);
PAINT ORANGE (810 180);
DISPLAY INVISIBLE (810 180);
FORCEPROP 2 LAST CDS_LOCATION C5A9
J 0
(850 200);
DISPLAY 0.617021 (850 200);
PAINT AQUA (850 200);
DISPLAY INVISIBLE (850 200);
FORCEPROP 2 LAST CDS_LIB dev_discrete
J 0
(800 100);
PAINT ORANGE (800 100);
DISPLAY INVISIBLE (800 100);
FORCEPROP 1 LAST PATH I208
J 0
(850 250);
DISPLAY 0.978723 (850 250);
PAINT WHITE (850 250);
DISPLAY INVISIBLE (850 250);
FORCEPROP 0 LAST ROOM PVDDQ_DEF
J 0
(850 300);
DISPLAY 1.021277 (850 300);
PAINT ORANGE (850 300);
DISPLAY INVISIBLE (850 300);
FORCEPROP 2 LAST CDS_SEC 1
J 0
(850 300);
PAINT MONO (850 300);
DISPLAY INVISIBLE (850 300);
FORCEPROP 2 LAST $SEC 1
J 0
(850 300);
PAINT MONO (850 300);
DISPLAY INVISIBLE (850 300);
FORCEADD CAP_A..1
(500 100);
FORCEPROP 1 LAST PACK_TYPE 0603V
J 0
(550 -100);
DISPLAY 0.617021 (550 -100);
PAINT SKYBLUE (550 -100);
FORCEPROP 1 LAST PART_NUMBER E15431-004
J 0
(550 -50);
DISPLAY 0.617021 (550 -50);
PAINT BLUE (550 -50);
FORCEPROP 1 LAST MATERIAL X6S
J 0
(550 0);
DISPLAY 0.617021 (550 0);
PAINT SKYBLUE (550 0);
FORCEPROP 1 LAST VOLTAGE 4V
J 0
(550 100);
DISPLAY 0.617021 (550 100);
PAINT SKYBLUE (550 100);
FORCEPROP 1 LAST TOLERANCE 20%
J 0
(550 50);
DISPLAY 0.617021 (550 50);
PAINT SKYBLUE (550 50);
FORCEPROP 1 LAST VALUE 22.0UF
J 0
(550 150);
DISPLAY 0.617021 (550 150);
PAINT SKYBLUE (550 150);
FORCEPROP 1 LAST LOCATION C5A8
J 0
(550 200);
DISPLAY 0.617021 (550 200);
PAINT AQUA (550 200);
FORCEPROP 1 LASTPIN (500 0) $PN 2
J 0
(510 -20);
DISPLAY 0.787234 (510 -20);
PAINT ORANGE (510 -20);
DISPLAY INVISIBLE (510 -20);
FORCEPROP 2 LAST CDS_LIB dev_discrete
J 0
(500 100);
PAINT ORANGE (500 100);
DISPLAY INVISIBLE (500 100);
FORCEPROP 1 LASTPIN (500 200) $PN 1
J 0
(510 180);
DISPLAY 0.787234 (510 180);
PAINT ORANGE (510 180);
DISPLAY INVISIBLE (510 180);
FORCEPROP 1 LAST PATH I209
J 0
(550 250);
DISPLAY 0.978723 (550 250);
PAINT WHITE (550 250);
DISPLAY INVISIBLE (550 250);
FORCEPROP 2 LAST $SEC 1
J 0
(550 300);
PAINT MONO (550 300);
DISPLAY INVISIBLE (550 300);
FORCEPROP 2 LAST CDS_SEC 1
J 0
(550 300);
PAINT MONO (550 300);
DISPLAY INVISIBLE (550 300);
FORCEPROP 2 LAST CDS_LOCATION C5A8
J 0
(550 200);
DISPLAY 0.617021 (550 200);
PAINT AQUA (550 200);
DISPLAY INVISIBLE (550 200);
FORCEPROP 0 LAST ROOM PVDDQ_DEF
J 0
(550 300);
DISPLAY 1.021277 (550 300);
PAINT ORANGE (550 300);
DISPLAY INVISIBLE (550 300);
FORCEADD CAP_A..1
(200 100);
FORCEPROP 1 LAST PACK_TYPE 0603V
J 0
(250 -100);
DISPLAY 0.617021 (250 -100);
PAINT SKYBLUE (250 -100);
FORCEPROP 1 LAST PART_NUMBER E15431-004
J 0
(250 -50);
DISPLAY 0.617021 (250 -50);
PAINT BLUE (250 -50);
FORCEPROP 1 LASTPIN (200 0) $PN 2
J 0
(210 -20);
DISPLAY 0.617021 (210 -20);
PAINT ORANGE (210 -20);
FORCEPROP 1 LAST MATERIAL X6S
J 0
(250 0);
DISPLAY 0.617021 (250 0);
PAINT SKYBLUE (250 0);
FORCEPROP 1 LASTPIN (200 200) $PN 1
J 0
(210 180);
DISPLAY 0.617021 (210 180);
PAINT ORANGE (210 180);
FORCEPROP 1 LAST VOLTAGE 4V
J 0
(250 100);
DISPLAY 0.617021 (250 100);
PAINT SKYBLUE (250 100);
FORCEPROP 1 LAST TOLERANCE 20%
J 0
(250 50);
DISPLAY 0.617021 (250 50);
PAINT SKYBLUE (250 50);
FORCEPROP 1 LAST VALUE 22.0UF
J 0
(250 150);
DISPLAY 0.617021 (250 150);
PAINT SKYBLUE (250 150);
FORCEPROP 1 LAST LOCATION C5A3
J 0
(250 200);
DISPLAY 0.617021 (250 200);
PAINT AQUA (250 200);
FORCEPROP 2 LAST CDS_LOCATION C5A3
J 0
(250 200);
DISPLAY 0.617021 (250 200);
PAINT AQUA (250 200);
DISPLAY INVISIBLE (250 200);
FORCEPROP 2 LAST CDS_LIB dev_discrete
J 0
(200 100);
PAINT ORANGE (200 100);
DISPLAY INVISIBLE (200 100);
FORCEPROP 2 LAST CDS_SEC 1
J 0
(250 250);
PAINT ORANGE (250 250);
DISPLAY INVISIBLE (250 250);
FORCEPROP 1 LAST PATH I210
J 0
(250 250);
DISPLAY 0.978723 (250 250);
PAINT WHITE (250 250);
DISPLAY INVISIBLE (250 250);
FORCEPROP 0 LAST ROOM PVDDQ_DEF
J 0
(250 300);
DISPLAY 1.021277 (250 300);
PAINT ORANGE (250 300);
DISPLAY INVISIBLE (250 300);
FORCEPROP 2 LAST SEC_TYPE 0603V
J 0
(250 300);
DISPLAY 1.021277 (250 300);
PAINT ORANGE (250 300);
DISPLAY INVISIBLE (250 300);
FORCEPROP 2 LAST SEC 1
J 0
(250 300);
DISPLAY 0.680851 (250 300);
PAINT MONO (250 300);
DISPLAY INVISIBLE (250 300);
FORCEADD CAP_A..1
(-125 100);
FORCEPROP 1 LAST VOLTAGE 4V
J 0
(-75 100);
DISPLAY 0.617021 (-75 100);
PAINT SKYBLUE (-75 100);
FORCEPROP 1 LAST MATERIAL X6S
J 0
(-75 0);
DISPLAY 0.617021 (-75 0);
PAINT SKYBLUE (-75 0);
FORCEPROP 1 LAST PACK_TYPE 0603V
J 0
(-75 -100);
DISPLAY 0.617021 (-75 -100);
PAINT SKYBLUE (-75 -100);
FORCEPROP 1 LAST TOLERANCE 20%
J 0
(-75 50);
DISPLAY 0.617021 (-75 50);
PAINT SKYBLUE (-75 50);
FORCEPROP 1 LAST VALUE 22.0UF
J 0
(-75 150);
DISPLAY 0.617021 (-75 150);
PAINT SKYBLUE (-75 150);
FORCEPROP 1 LAST PART_NUMBER E15431-004
J 0
(-75 -50);
DISPLAY 0.617021 (-75 -50);
PAINT BLUE (-75 -50);
FORCEPROP 1 LAST LOCATION C5A7
J 0
(-75 200);
DISPLAY 0.617021 (-75 200);
PAINT AQUA (-75 200);
FORCEPROP 1 LASTPIN (-125 0) $PN 2
J 0
(-115 -20);
DISPLAY 0.787234 (-115 -20);
PAINT ORANGE (-115 -20);
DISPLAY INVISIBLE (-115 -20);
FORCEPROP 1 LASTPIN (-125 200) $PN 1
J 0
(-115 180);
DISPLAY 0.787234 (-115 180);
PAINT ORANGE (-115 180);
DISPLAY INVISIBLE (-115 180);
FORCEPROP 2 LAST CDS_LOCATION C5A7
J 0
(-75 200);
DISPLAY 0.617021 (-75 200);
PAINT AQUA (-75 200);
DISPLAY INVISIBLE (-75 200);
FORCEPROP 2 LAST CDS_LIB dev_discrete
J 0
(-125 100);
PAINT ORANGE (-125 100);
DISPLAY INVISIBLE (-125 100);
FORCEPROP 1 LAST PATH I211
J 0
(-75 250);
DISPLAY 0.978723 (-75 250);
PAINT WHITE (-75 250);
DISPLAY INVISIBLE (-75 250);
FORCEPROP 0 LAST ROOM PVDDQ_DEF
J 0
(-75 300);
DISPLAY 1.021277 (-75 300);
PAINT ORANGE (-75 300);
DISPLAY INVISIBLE (-75 300);
FORCEPROP 2 LAST CDS_SEC 1
J 0
(-75 300);
PAINT MONO (-75 300);
DISPLAY INVISIBLE (-75 300);
FORCEPROP 2 LAST $SEC 1
J 0
(-75 300);
PAINT MONO (-75 300);
DISPLAY INVISIBLE (-75 300);
FORCEADD CAP_A..1
(-400 100);
FORCEPROP 1 LAST PART_NUMBER E15431-004
J 0
(-350 -50);
DISPLAY 0.617021 (-350 -50);
PAINT BLUE (-350 -50);
FORCEPROP 1 LAST PACK_TYPE 0603V
J 0
(-350 -100);
DISPLAY 0.617021 (-350 -100);
PAINT SKYBLUE (-350 -100);
FORCEPROP 1 LAST MATERIAL X6S
J 0
(-350 0);
DISPLAY 0.617021 (-350 0);
PAINT SKYBLUE (-350 0);
FORCEPROP 1 LAST VOLTAGE 4V
J 0
(-350 100);
DISPLAY 0.617021 (-350 100);
PAINT SKYBLUE (-350 100);
FORCEPROP 1 LAST TOLERANCE 20%
J 0
(-350 50);
DISPLAY 0.617021 (-350 50);
PAINT SKYBLUE (-350 50);
FORCEPROP 1 LAST VALUE 22.0UF
J 0
(-350 150);
DISPLAY 0.617021 (-350 150);
PAINT SKYBLUE (-350 150);
FORCEPROP 1 LAST LOCATION C5A6
J 0
(-350 200);
DISPLAY 0.617021 (-350 200);
PAINT AQUA (-350 200);
FORCEPROP 1 LASTPIN (-400 0) $PN 2
J 0
(-390 -20);
DISPLAY 0.787234 (-390 -20);
PAINT ORANGE (-390 -20);
DISPLAY INVISIBLE (-390 -20);
FORCEPROP 2 LAST CDS_LIB dev_discrete
J 0
(-400 100);
PAINT ORANGE (-400 100);
DISPLAY INVISIBLE (-400 100);
FORCEPROP 1 LASTPIN (-400 200) $PN 1
J 0
(-390 180);
DISPLAY 0.787234 (-390 180);
PAINT ORANGE (-390 180);
DISPLAY INVISIBLE (-390 180);
FORCEPROP 2 LAST CDS_LOCATION C5A6
J 0
(-350 200);
DISPLAY 0.617021 (-350 200);
PAINT AQUA (-350 200);
DISPLAY INVISIBLE (-350 200);
FORCEPROP 1 LAST PATH I212
J 0
(-350 250);
DISPLAY 0.978723 (-350 250);
PAINT WHITE (-350 250);
DISPLAY INVISIBLE (-350 250);
FORCEPROP 0 LAST ROOM PVDDQ_DEF
J 0
(-350 300);
DISPLAY 1.021277 (-350 300);
PAINT ORANGE (-350 300);
DISPLAY INVISIBLE (-350 300);
FORCEPROP 2 LAST CDS_SEC 1
J 0
(-350 300);
PAINT MONO (-350 300);
DISPLAY INVISIBLE (-350 300);
FORCEPROP 2 LAST $SEC 1
J 0
(-350 300);
PAINT MONO (-350 300);
DISPLAY INVISIBLE (-350 300);
FORCEADD CAP_A..1
(-700 100);
FORCEPROP 1 LAST PACK_TYPE 0603V
J 0
(-650 -100);
DISPLAY 0.617021 (-650 -100);
PAINT SKYBLUE (-650 -100);
FORCEPROP 1 LAST PART_NUMBER E15431-004
J 0
(-650 -50);
DISPLAY 0.617021 (-650 -50);
PAINT BLUE (-650 -50);
FORCEPROP 1 LAST MATERIAL X6S
J 0
(-650 0);
DISPLAY 0.617021 (-650 0);
PAINT SKYBLUE (-650 0);
FORCEPROP 1 LAST VOLTAGE 4V
J 0
(-650 100);
DISPLAY 0.617021 (-650 100);
PAINT SKYBLUE (-650 100);
FORCEPROP 1 LAST TOLERANCE 20%
J 0
(-650 50);
DISPLAY 0.617021 (-650 50);
PAINT SKYBLUE (-650 50);
FORCEPROP 1 LAST VALUE 22.0UF
J 0
(-650 150);
DISPLAY 0.617021 (-650 150);
PAINT SKYBLUE (-650 150);
FORCEPROP 1 LAST LOCATION C5A14
J 0
(-650 200);
DISPLAY 0.617021 (-650 200);
PAINT AQUA (-650 200);
FORCEPROP 1 LASTPIN (-700 0) $PN 2
J 0
(-690 -20);
DISPLAY 0.787234 (-690 -20);
PAINT ORANGE (-690 -20);
DISPLAY INVISIBLE (-690 -20);
FORCEPROP 2 LAST CDS_LIB dev_discrete
J 0
(-700 100);
PAINT ORANGE (-700 100);
DISPLAY INVISIBLE (-700 100);
FORCEPROP 2 LAST CDS_LOCATION C5A14
J 0
(-650 200);
DISPLAY 0.617021 (-650 200);
PAINT AQUA (-650 200);
DISPLAY INVISIBLE (-650 200);
FORCEPROP 1 LASTPIN (-700 200) $PN 1
J 0
(-690 180);
DISPLAY 0.787234 (-690 180);
PAINT ORANGE (-690 180);
DISPLAY INVISIBLE (-690 180);
FORCEPROP 1 LAST PATH I213
J 0
(-650 250);
DISPLAY 0.978723 (-650 250);
PAINT WHITE (-650 250);
DISPLAY INVISIBLE (-650 250);
FORCEPROP 0 LAST ROOM PVDDQ_DEF
J 0
(-650 300);
DISPLAY 1.021277 (-650 300);
PAINT ORANGE (-650 300);
DISPLAY INVISIBLE (-650 300);
FORCEPROP 2 LAST CDS_SEC 1
J 0
(-650 300);
PAINT MONO (-650 300);
DISPLAY INVISIBLE (-650 300);
FORCEPROP 2 LAST $SEC 1
J 0
(-650 300);
PAINT MONO (-650 300);
DISPLAY INVISIBLE (-650 300);
FORCEADD CAP_A..1
(-1000 100);
FORCEPROP 1 LAST PACK_TYPE 0603V
J 0
(-950 -100);
DISPLAY 0.617021 (-950 -100);
PAINT SKYBLUE (-950 -100);
FORCEPROP 1 LAST PART_NUMBER E15431-004
J 0
(-950 -50);
DISPLAY 0.617021 (-950 -50);
PAINT BLUE (-950 -50);
FORCEPROP 1 LASTPIN (-1000 0) $PN 2
J 0
(-990 -20);
DISPLAY 0.617021 (-990 -20);
PAINT ORANGE (-990 -20);
FORCEPROP 1 LAST MATERIAL X6S
J 0
(-950 0);
DISPLAY 0.617021 (-950 0);
PAINT SKYBLUE (-950 0);
FORCEPROP 1 LASTPIN (-1000 200) $PN 1
J 0
(-990 180);
DISPLAY 0.617021 (-990 180);
PAINT ORANGE (-990 180);
FORCEPROP 1 LAST VOLTAGE 4V
J 0
(-950 100);
DISPLAY 0.617021 (-950 100);
PAINT SKYBLUE (-950 100);
FORCEPROP 1 LAST TOLERANCE 20%
J 0
(-950 50);
DISPLAY 0.617021 (-950 50);
PAINT SKYBLUE (-950 50);
FORCEPROP 1 LAST VALUE 22.0UF
J 0
(-950 150);
DISPLAY 0.617021 (-950 150);
PAINT SKYBLUE (-950 150);
FORCEPROP 1 LAST LOCATION C5A2
J 0
(-950 200);
DISPLAY 0.617021 (-950 200);
PAINT AQUA (-950 200);
FORCEPROP 2 LAST CDS_LIB dev_discrete
J 0
(-1000 100);
PAINT ORANGE (-1000 100);
DISPLAY INVISIBLE (-1000 100);
FORCEPROP 2 LAST CDS_LOCATION C5A2
J 0
(-950 200);
DISPLAY 0.617021 (-950 200);
PAINT AQUA (-950 200);
DISPLAY INVISIBLE (-950 200);
FORCEPROP 2 LAST CDS_SEC 1
J 0
(-950 250);
PAINT ORANGE (-950 250);
DISPLAY INVISIBLE (-950 250);
FORCEPROP 1 LAST PATH I214
J 0
(-950 250);
DISPLAY 0.978723 (-950 250);
PAINT WHITE (-950 250);
DISPLAY INVISIBLE (-950 250);
FORCEPROP 0 LAST ROOM PVDDQ_DEF
J 0
(-950 300);
DISPLAY 1.021277 (-950 300);
PAINT ORANGE (-950 300);
DISPLAY INVISIBLE (-950 300);
FORCEPROP 2 LAST SEC_TYPE 0603V
J 0
(-950 300);
DISPLAY 1.021277 (-950 300);
PAINT ORANGE (-950 300);
DISPLAY INVISIBLE (-950 300);
FORCEPROP 2 LAST SEC 1
J 0
(-950 300);
DISPLAY 0.680851 (-950 300);
PAINT MONO (-950 300);
DISPLAY INVISIBLE (-950 300);
FORCEADD CAP_A..1
(-1275 100);
FORCEPROP 1 LAST PACK_TYPE 0603V
J 0
(-1225 -100);
DISPLAY 0.617021 (-1225 -100);
PAINT SKYBLUE (-1225 -100);
FORCEPROP 1 LAST PART_NUMBER E15431-004
J 0
(-1225 -50);
DISPLAY 0.617021 (-1225 -50);
PAINT BLUE (-1225 -50);
FORCEPROP 1 LAST MATERIAL X6S
J 0
(-1225 0);
DISPLAY 0.617021 (-1225 0);
PAINT SKYBLUE (-1225 0);
FORCEPROP 1 LAST LOCATION C5A13
J 0
(-1225 200);
DISPLAY 0.617021 (-1225 200);
PAINT AQUA (-1225 200);
FORCEPROP 1 LAST VALUE 22.0UF
J 0
(-1225 150);
DISPLAY 0.617021 (-1225 150);
PAINT SKYBLUE (-1225 150);
FORCEPROP 1 LAST VOLTAGE 4V
J 0
(-1225 100);
DISPLAY 0.617021 (-1225 100);
PAINT SKYBLUE (-1225 100);
FORCEPROP 1 LAST TOLERANCE 20%
J 0
(-1225 50);
DISPLAY 0.617021 (-1225 50);
PAINT SKYBLUE (-1225 50);
FORCEPROP 1 LASTPIN (-1275 0) $PN 2
J 0
(-1265 -20);
DISPLAY 0.787234 (-1265 -20);
PAINT ORANGE (-1265 -20);
DISPLAY INVISIBLE (-1265 -20);
FORCEPROP 1 LASTPIN (-1275 200) $PN 1
J 0
(-1265 180);
DISPLAY 0.787234 (-1265 180);
PAINT ORANGE (-1265 180);
DISPLAY INVISIBLE (-1265 180);
FORCEPROP 2 LAST CDS_LOCATION C5A13
J 0
(-1225 200);
DISPLAY 0.617021 (-1225 200);
PAINT AQUA (-1225 200);
DISPLAY INVISIBLE (-1225 200);
FORCEPROP 2 LAST CDS_LIB dev_discrete
J 0
(-1275 100);
PAINT ORANGE (-1275 100);
DISPLAY INVISIBLE (-1275 100);
FORCEPROP 1 LAST PATH I215
J 0
(-1225 250);
DISPLAY 0.978723 (-1225 250);
PAINT WHITE (-1225 250);
DISPLAY INVISIBLE (-1225 250);
FORCEPROP 0 LAST ROOM PVDDQ_DEF
J 0
(-1225 300);
DISPLAY 1.021277 (-1225 300);
PAINT ORANGE (-1225 300);
DISPLAY INVISIBLE (-1225 300);
FORCEPROP 2 LAST $SEC 1
J 0
(-1225 300);
PAINT MONO (-1225 300);
DISPLAY INVISIBLE (-1225 300);
FORCEPROP 2 LAST CDS_SEC 1
J 0
(-1225 300);
PAINT MONO (-1225 300);
DISPLAY INVISIBLE (-1225 300);
FORCEADD CAP_A..1
(-1550 100);
FORCEPROP 1 LAST PACK_TYPE 0603V
J 0
(-1500 -100);
DISPLAY 0.617021 (-1500 -100);
PAINT SKYBLUE (-1500 -100);
FORCEPROP 1 LAST PART_NUMBER E15431-004
J 0
(-1500 -50);
DISPLAY 0.617021 (-1500 -50);
PAINT BLUE (-1500 -50);
FORCEPROP 1 LAST MATERIAL X6S
J 0
(-1500 0);
DISPLAY 0.617021 (-1500 0);
PAINT SKYBLUE (-1500 0);
FORCEPROP 1 LAST LOCATION C5A12
J 0
(-1500 200);
DISPLAY 0.617021 (-1500 200);
PAINT AQUA (-1500 200);
FORCEPROP 1 LAST VALUE 22.0UF
J 0
(-1500 150);
DISPLAY 0.617021 (-1500 150);
PAINT SKYBLUE (-1500 150);
FORCEPROP 1 LAST TOLERANCE 20%
J 0
(-1500 50);
DISPLAY 0.617021 (-1500 50);
PAINT SKYBLUE (-1500 50);
FORCEPROP 1 LAST VOLTAGE 4V
J 0
(-1500 100);
DISPLAY 0.617021 (-1500 100);
PAINT SKYBLUE (-1500 100);
FORCEPROP 1 LASTPIN (-1550 0) $PN 2
J 0
(-1540 -20);
DISPLAY 0.787234 (-1540 -20);
PAINT ORANGE (-1540 -20);
DISPLAY INVISIBLE (-1540 -20);
FORCEPROP 2 LAST CDS_LIB dev_discrete
J 0
(-1550 100);
PAINT ORANGE (-1550 100);
DISPLAY INVISIBLE (-1550 100);
FORCEPROP 1 LASTPIN (-1550 200) $PN 1
J 0
(-1540 180);
DISPLAY 0.787234 (-1540 180);
PAINT ORANGE (-1540 180);
DISPLAY INVISIBLE (-1540 180);
FORCEPROP 0 LAST ROOM PVDDQ_DEF
J 0
(-1500 300);
DISPLAY 1.021277 (-1500 300);
PAINT ORANGE (-1500 300);
DISPLAY INVISIBLE (-1500 300);
FORCEPROP 2 LAST CDS_LOCATION C5A12
J 0
(-1500 200);
DISPLAY 0.617021 (-1500 200);
PAINT AQUA (-1500 200);
DISPLAY INVISIBLE (-1500 200);
FORCEPROP 2 LAST CDS_SEC 1
J 0
(-1500 300);
PAINT MONO (-1500 300);
DISPLAY INVISIBLE (-1500 300);
FORCEPROP 2 LAST $SEC 1
J 0
(-1500 300);
PAINT MONO (-1500 300);
DISPLAY INVISIBLE (-1500 300);
FORCEPROP 1 LAST PATH I216
J 0
(-1500 250);
DISPLAY 0.978723 (-1500 250);
PAINT WHITE (-1500 250);
DISPLAY INVISIBLE (-1500 250);
FORCEADD CAP_A..1
(-1850 100);
FORCEPROP 1 LAST PACK_TYPE 0603V
J 0
(-1800 -100);
DISPLAY 0.617021 (-1800 -100);
PAINT SKYBLUE (-1800 -100);
FORCEPROP 1 LAST PART_NUMBER E15431-004
J 0
(-1800 -50);
DISPLAY 0.617021 (-1800 -50);
PAINT BLUE (-1800 -50);
FORCEPROP 1 LAST MATERIAL X6S
J 0
(-1800 0);
DISPLAY 0.617021 (-1800 0);
PAINT SKYBLUE (-1800 0);
FORCEPROP 1 LAST VOLTAGE 4V
J 0
(-1800 100);
DISPLAY 0.617021 (-1800 100);
PAINT SKYBLUE (-1800 100);
FORCEPROP 1 LAST TOLERANCE 20%
J 0
(-1800 50);
DISPLAY 0.617021 (-1800 50);
PAINT SKYBLUE (-1800 50);
FORCEPROP 1 LAST VALUE 22.0UF
J 0
(-1800 150);
DISPLAY 0.617021 (-1800 150);
PAINT SKYBLUE (-1800 150);
FORCEPROP 1 LAST LOCATION C5A15
J 0
(-1800 200);
DISPLAY 0.617021 (-1800 200);
PAINT AQUA (-1800 200);
FORCEPROP 1 LASTPIN (-1850 0) $PN 2
J 0
(-1840 -20);
DISPLAY 0.787234 (-1840 -20);
PAINT ORANGE (-1840 -20);
DISPLAY INVISIBLE (-1840 -20);
FORCEPROP 1 LASTPIN (-1850 200) $PN 1
J 0
(-1840 180);
DISPLAY 0.787234 (-1840 180);
PAINT ORANGE (-1840 180);
DISPLAY INVISIBLE (-1840 180);
FORCEPROP 2 LAST CDS_LOCATION C5A15
J 0
(-1800 200);
DISPLAY 0.617021 (-1800 200);
PAINT AQUA (-1800 200);
DISPLAY INVISIBLE (-1800 200);
FORCEPROP 2 LAST CDS_LIB dev_discrete
J 0
(-1850 100);
PAINT ORANGE (-1850 100);
DISPLAY INVISIBLE (-1850 100);
FORCEPROP 1 LAST PATH I217
J 0
(-1800 250);
DISPLAY 0.978723 (-1800 250);
PAINT WHITE (-1800 250);
DISPLAY INVISIBLE (-1800 250);
FORCEPROP 0 LAST ROOM PVDDQ_DEF
J 0
(-1800 300);
DISPLAY 1.021277 (-1800 300);
PAINT ORANGE (-1800 300);
DISPLAY INVISIBLE (-1800 300);
FORCEPROP 2 LAST CDS_SEC 1
J 0
(-1800 300);
PAINT MONO (-1800 300);
DISPLAY INVISIBLE (-1800 300);
FORCEPROP 2 LAST $SEC 1
J 0
(-1800 300);
PAINT MONO (-1800 300);
DISPLAY INVISIBLE (-1800 300);
FORCEADD PVDDQ_DEF..1
(-2150 350);
FORCEPROP 3 LASTPIN (-2150 300) SIG_NAME PVDDQ_DEF\g
J 0
(-2140 310);
DISPLAY 0.659574 (-2140 310);
PAINT MONO (-2140 310);
DISPLAY INVISIBLE (-2140 310);
FORCEPROP 1 LAST PATH I218
J 0
(-2100 375);
DISPLAY 0.872340 (-2100 375);
PAINT AQUA (-2100 375);
DISPLAY INVISIBLE (-2100 375);
FORCEPROP 1 LAST BODY_TYPE PLUMBING
J 0
(-2195 307);
DISPLAY 0.340426 (-2195 307);
PAINT GREEN (-2195 307);
DISPLAY INVISIBLE (-2195 307);
FORCEPROP 2 LAST CDS_LIB mstr_symbols
J 0
(-2150 350);
PAINT ORANGE (-2150 350);
DISPLAY INVISIBLE (-2150 350);
FORCEPROP 1 LAST HDL_POWER PVDDQ_DEF
J 1
(-2150 400);
DISPLAY 0.872340 (-2150 400);
PAINT GREEN (-2150 400);
DISPLAY INVISIBLE (-2150 400);
FORCEPROP 1 LAST VOLTAGE 1.2V
J 0
(-2195 307);
DISPLAY 0.340426 (-2195 307);
PAINT SKYBLUE (-2195 307);
DISPLAY INVISIBLE (-2195 307);
FORCEADD CAP_A..1
(-2150 100);
FORCEPROP 1 LAST PACK_TYPE 0603V
J 0
(-2100 -100);
DISPLAY 0.617021 (-2100 -100);
PAINT SKYBLUE (-2100 -100);
FORCEPROP 1 LAST PART_NUMBER E15431-004
J 0
(-2100 -50);
DISPLAY 0.617021 (-2100 -50);
PAINT BLUE (-2100 -50);
FORCEPROP 1 LASTPIN (-2150 0) $PN 2
J 0
(-2140 -20);
DISPLAY 0.617021 (-2140 -20);
PAINT ORANGE (-2140 -20);
FORCEPROP 1 LAST MATERIAL X6S
J 0
(-2100 0);
DISPLAY 0.617021 (-2100 0);
PAINT SKYBLUE (-2100 0);
FORCEPROP 1 LASTPIN (-2150 200) $PN 1
J 0
(-2140 180);
DISPLAY 0.617021 (-2140 180);
PAINT ORANGE (-2140 180);
FORCEPROP 1 LAST VOLTAGE 4V
J 0
(-2100 100);
DISPLAY 0.617021 (-2100 100);
PAINT SKYBLUE (-2100 100);
FORCEPROP 1 LAST TOLERANCE 20%
J 0
(-2100 50);
DISPLAY 0.617021 (-2100 50);
PAINT SKYBLUE (-2100 50);
FORCEPROP 1 LAST VALUE 22.0UF
J 0
(-2100 150);
DISPLAY 0.617021 (-2100 150);
PAINT SKYBLUE (-2100 150);
FORCEPROP 1 LAST LOCATION C5A1
J 0
(-2100 200);
DISPLAY 0.617021 (-2100 200);
PAINT AQUA (-2100 200);
FORCEPROP 2 LAST CDS_LIB dev_discrete
J 0
(-2150 100);
PAINT ORANGE (-2150 100);
DISPLAY INVISIBLE (-2150 100);
FORCEPROP 2 LAST CDS_LOCATION C5A1
J 0
(-2100 200);
DISPLAY 0.617021 (-2100 200);
PAINT AQUA (-2100 200);
DISPLAY INVISIBLE (-2100 200);
FORCEPROP 1 LAST PATH I219
J 0
(-2100 250);
DISPLAY 0.978723 (-2100 250);
PAINT WHITE (-2100 250);
DISPLAY INVISIBLE (-2100 250);
FORCEPROP 2 LAST CDS_SEC 1
J 0
(-2100 250);
PAINT ORANGE (-2100 250);
DISPLAY INVISIBLE (-2100 250);
FORCEPROP 2 LAST SEC_TYPE 0603V
J 0
(-2100 300);
DISPLAY 1.021277 (-2100 300);
PAINT ORANGE (-2100 300);
DISPLAY INVISIBLE (-2100 300);
FORCEPROP 2 LAST SEC 1
J 0
(-2100 300);
DISPLAY 0.680851 (-2100 300);
PAINT MONO (-2100 300);
DISPLAY INVISIBLE (-2100 300);
FORCEPROP 0 LAST ROOM PVDDQ_DEF
J 0
(-2100 300);
DISPLAY 1.021277 (-2100 300);
PAINT ORANGE (-2100 300);
DISPLAY INVISIBLE (-2100 300);
FORCEADD GND..1
(-2150 -175);
FORCEPROP 3 LASTPIN (-2150 -125) SIG_NAME GND\g
J 0
(-2140 -115);
DISPLAY 0.659574 (-2140 -115);
PAINT MONO (-2140 -115);
DISPLAY INVISIBLE (-2140 -115);
FORCEPROP 2 LAST ROOM VDDQ_ABC_PWR_VR
J 0
(-2700 -100);
DISPLAY 1.936170 (-2700 -100);
PAINT ORANGE (-2700 -100);
DISPLAY INVISIBLE (-2700 -100);
FORCEPROP 2 LAST BOM_COST PROC_VRD_VCCIN_CPU0
J 0
(-2525 -100);
DISPLAY 1.446809 (-2525 -100);
PAINT MONO (-2525 -100);
DISPLAY INVISIBLE (-2525 -100);
FORCEPROP 1 LAST BODY_TYPE PLUMBING
J 0
(-2195 -218);
DISPLAY 0.340426 (-2195 -218);
PAINT GREEN (-2195 -218);
DISPLAY INVISIBLE (-2195 -218);
FORCEPROP 1 LAST PATH I220
J 0
(-2075 -175);
DISPLAY 0.872340 (-2075 -175);
PAINT AQUA (-2075 -175);
DISPLAY INVISIBLE (-2075 -175);
FORCEPROP 2 LAST CDS_LIB mstr_symbols
J 0
(-2150 -175);
PAINT ORANGE (-2150 -175);
DISPLAY INVISIBLE (-2150 -175);
FORCEPROP 1 LAST SIZE 1B
J 0
(-2075 -225);
DISPLAY 1.723404 (-2075 -225);
PAINT GREEN (-2075 -225);
DISPLAY INVISIBLE (-2075 -225);
FORCEPROP 1 LAST VOLTAGE 0
J 0
(-2150 -175);
PAINT SKYBLUE (-2150 -175);
DISPLAY INVISIBLE (-2150 -175);
FORCEPROP 1 LAST HDL_POWER GND
J 0
(-2150 -25);
DISPLAY 1.723404 (-2150 -25);
PAINT GREEN (-2150 -25);
DISPLAY INVISIBLE (-2150 -25);
FORCEADD CAP_A..1
(2225 -650);
FORCEPROP 1 LAST MATERIAL X6S
J 0
(2275 -750);
DISPLAY 0.617021 (2275 -750);
PAINT SKYBLUE (2275 -750);
FORCEPROP 1 LAST VOLTAGE 4V
J 0
(2275 -650);
DISPLAY 0.617021 (2275 -650);
PAINT SKYBLUE (2275 -650);
FORCEPROP 1 LAST PACK_TYPE 0603V
J 0
(2275 -850);
DISPLAY 0.617021 (2275 -850);
PAINT SKYBLUE (2275 -850);
FORCEPROP 1 LAST TOLERANCE 20%
J 0
(2275 -700);
DISPLAY 0.617021 (2275 -700);
PAINT SKYBLUE (2275 -700);
FORCEPROP 1 LAST VALUE 22.0UF
J 0
(2275 -600);
DISPLAY 0.617021 (2275 -600);
PAINT SKYBLUE (2275 -600);
FORCEPROP 1 LAST LOCATION C5A11
J 0
(2275 -550);
DISPLAY 0.617021 (2275 -550);
PAINT AQUA (2275 -550);
FORCEPROP 1 LAST PART_NUMBER E15431-004
J 0
(2275 -800);
DISPLAY 0.617021 (2275 -800);
PAINT BLUE (2275 -800);
FORCEPROP 1 LASTPIN (2225 -550) $PN 1
J 0
(2235 -570);
DISPLAY 0.787234 (2235 -570);
PAINT ORANGE (2235 -570);
DISPLAY INVISIBLE (2235 -570);
FORCEPROP 2 LAST CDS_LIB dev_discrete
J 0
(2225 -650);
PAINT ORANGE (2225 -650);
DISPLAY INVISIBLE (2225 -650);
FORCEPROP 2 LAST CDS_LOCATION C5A11
J 0
(2275 -550);
DISPLAY 0.617021 (2275 -550);
PAINT AQUA (2275 -550);
DISPLAY INVISIBLE (2275 -550);
FORCEPROP 1 LASTPIN (2225 -750) $PN 2
J 0
(2235 -770);
DISPLAY 0.787234 (2235 -770);
PAINT ORANGE (2235 -770);
DISPLAY INVISIBLE (2235 -770);
FORCEPROP 2 LAST $SEC 1
J 0
(2275 -450);
PAINT MONO (2275 -450);
DISPLAY INVISIBLE (2275 -450);
FORCEPROP 1 LAST PATH I221
J 0
(2275 -500);
DISPLAY 0.978723 (2275 -500);
PAINT WHITE (2275 -500);
DISPLAY INVISIBLE (2275 -500);
FORCEPROP 2 LAST CDS_SEC 1
J 0
(2275 -450);
PAINT MONO (2275 -450);
DISPLAY INVISIBLE (2275 -450);
FORCEPROP 0 LAST ROOM PVDDQ_DEF
J 0
(2275 -450);
DISPLAY 1.021277 (2275 -450);
PAINT ORANGE (2275 -450);
DISPLAY INVISIBLE (2275 -450);
FORCEADD CAP_A..1
(1950 -650);
FORCEPROP 1 LAST MATERIAL X6S
J 0
(2000 -750);
DISPLAY 0.617021 (2000 -750);
PAINT SKYBLUE (2000 -750);
FORCEPROP 1 LAST VOLTAGE 4V
J 0
(2000 -650);
DISPLAY 0.617021 (2000 -650);
PAINT SKYBLUE (2000 -650);
FORCEPROP 1 LAST PACK_TYPE 0603V
J 0
(2000 -850);
DISPLAY 0.617021 (2000 -850);
PAINT SKYBLUE (2000 -850);
FORCEPROP 1 LAST TOLERANCE 20%
J 0
(2000 -700);
DISPLAY 0.617021 (2000 -700);
PAINT SKYBLUE (2000 -700);
FORCEPROP 1 LAST VALUE 22.0UF
J 0
(2000 -600);
DISPLAY 0.617021 (2000 -600);
PAINT SKYBLUE (2000 -600);
FORCEPROP 1 LAST PART_NUMBER E15431-004
J 0
(2000 -800);
DISPLAY 0.617021 (2000 -800);
PAINT BLUE (2000 -800);
FORCEPROP 1 LAST LOCATION C4M2
J 0
(2000 -550);
DISPLAY 0.617021 (2000 -550);
PAINT AQUA (2000 -550);
FORCEPROP 1 LASTPIN (1950 -750) $PN 2
J 0
(1960 -770);
DISPLAY 0.787234 (1960 -770);
PAINT ORANGE (1960 -770);
DISPLAY INVISIBLE (1960 -770);
FORCEPROP 1 LASTPIN (1950 -550) $PN 1
J 0
(1960 -570);
DISPLAY 0.787234 (1960 -570);
PAINT ORANGE (1960 -570);
DISPLAY INVISIBLE (1960 -570);
FORCEPROP 2 LAST CDS_LOCATION C4M2
J 0
(2000 -550);
DISPLAY 0.617021 (2000 -550);
PAINT AQUA (2000 -550);
DISPLAY INVISIBLE (2000 -550);
FORCEPROP 2 LAST CDS_LIB dev_discrete
J 0
(1950 -650);
PAINT ORANGE (1950 -650);
DISPLAY INVISIBLE (1950 -650);
FORCEPROP 0 LAST ROOM PVDDQ_DEF
J 0
(2000 -450);
DISPLAY 1.021277 (2000 -450);
PAINT ORANGE (2000 -450);
DISPLAY INVISIBLE (2000 -450);
FORCEPROP 2 LAST CDS_SEC 1
J 0
(2000 -450);
PAINT MONO (2000 -450);
DISPLAY INVISIBLE (2000 -450);
FORCEPROP 2 LAST $SEC 1
J 0
(2000 -450);
PAINT MONO (2000 -450);
DISPLAY INVISIBLE (2000 -450);
FORCEPROP 1 LAST PATH I222
J 0
(2000 -500);
DISPLAY 0.978723 (2000 -500);
PAINT WHITE (2000 -500);
DISPLAY INVISIBLE (2000 -500);
FORCEADD CAP_A..1
(1650 -650);
FORCEPROP 1 LAST TOLERANCE 20%
J 0
(1700 -700);
DISPLAY 0.617021 (1700 -700);
PAINT SKYBLUE (1700 -700);
FORCEPROP 1 LAST VOLTAGE 4V
J 0
(1700 -650);
DISPLAY 0.617021 (1700 -650);
PAINT SKYBLUE (1700 -650);
FORCEPROP 1 LAST MATERIAL X6S
J 0
(1700 -750);
DISPLAY 0.617021 (1700 -750);
PAINT SKYBLUE (1700 -750);
FORCEPROP 1 LAST PACK_TYPE 0603V
J 0
(1700 -850);
DISPLAY 0.617021 (1700 -850);
PAINT SKYBLUE (1700 -850);
FORCEPROP 1 LAST VALUE 22.0UF
J 0
(1700 -600);
DISPLAY 0.617021 (1700 -600);
PAINT SKYBLUE (1700 -600);
FORCEPROP 1 LAST PART_NUMBER E15431-004
J 0
(1700 -800);
DISPLAY 0.617021 (1700 -800);
PAINT BLUE (1700 -800);
FORCEPROP 1 LAST LOCATION C5M1
J 0
(1700 -550);
DISPLAY 0.617021 (1700 -550);
PAINT AQUA (1700 -550);
FORCEPROP 1 LASTPIN (1650 -750) $PN 2
J 0
(1660 -770);
DISPLAY 0.787234 (1660 -770);
PAINT ORANGE (1660 -770);
DISPLAY INVISIBLE (1660 -770);
FORCEPROP 1 LASTPIN (1650 -550) $PN 1
J 0
(1660 -570);
DISPLAY 0.787234 (1660 -570);
PAINT ORANGE (1660 -570);
DISPLAY INVISIBLE (1660 -570);
FORCEPROP 2 LAST CDS_LOCATION C5M1
J 0
(1700 -550);
DISPLAY 0.617021 (1700 -550);
PAINT AQUA (1700 -550);
DISPLAY INVISIBLE (1700 -550);
FORCEPROP 2 LAST CDS_LIB dev_discrete
J 0
(1650 -650);
PAINT ORANGE (1650 -650);
DISPLAY INVISIBLE (1650 -650);
FORCEPROP 0 LAST ROOM PVDDQ_DEF
J 0
(1700 -450);
DISPLAY 1.021277 (1700 -450);
PAINT ORANGE (1700 -450);
DISPLAY INVISIBLE (1700 -450);
FORCEPROP 2 LAST CDS_SEC 1
J 0
(1700 -450);
PAINT MONO (1700 -450);
DISPLAY INVISIBLE (1700 -450);
FORCEPROP 2 LAST $SEC 1
J 0
(1700 -450);
PAINT MONO (1700 -450);
DISPLAY INVISIBLE (1700 -450);
FORCEPROP 1 LAST PATH I223
J 0
(1700 -500);
DISPLAY 0.978723 (1700 -500);
PAINT WHITE (1700 -500);
DISPLAY INVISIBLE (1700 -500);
FORCEADD CAP_A..1
(1350 -650);
FORCEPROP 1 LAST LOCATION C5M2
J 0
(1400 -550);
DISPLAY 0.617021 (1400 -550);
PAINT AQUA (1400 -550);
FORCEPROP 1 LAST TOLERANCE 20%
J 0
(1400 -700);
DISPLAY 0.617021 (1400 -700);
PAINT SKYBLUE (1400 -700);
FORCEPROP 1 LAST VOLTAGE 4V
J 0
(1400 -650);
DISPLAY 0.617021 (1400 -650);
PAINT SKYBLUE (1400 -650);
FORCEPROP 1 LAST MATERIAL X6S
J 0
(1400 -750);
DISPLAY 0.617021 (1400 -750);
PAINT SKYBLUE (1400 -750);
FORCEPROP 1 LAST PACK_TYPE 0603V
J 0
(1400 -850);
DISPLAY 0.617021 (1400 -850);
PAINT SKYBLUE (1400 -850);
FORCEPROP 1 LAST VALUE 22.0UF
J 0
(1400 -600);
DISPLAY 0.617021 (1400 -600);
PAINT SKYBLUE (1400 -600);
FORCEPROP 1 LAST PART_NUMBER E15431-004
J 0
(1400 -800);
DISPLAY 0.617021 (1400 -800);
PAINT BLUE (1400 -800);
FORCEPROP 1 LASTPIN (1350 -750) $PN 2
J 0
(1360 -770);
DISPLAY 0.787234 (1360 -770);
PAINT ORANGE (1360 -770);
DISPLAY INVISIBLE (1360 -770);
FORCEPROP 1 LASTPIN (1350 -550) $PN 1
J 0
(1360 -570);
DISPLAY 0.787234 (1360 -570);
PAINT ORANGE (1360 -570);
DISPLAY INVISIBLE (1360 -570);
FORCEPROP 2 LAST CDS_LOCATION C5M2
J 0
(1400 -550);
DISPLAY 0.617021 (1400 -550);
PAINT AQUA (1400 -550);
DISPLAY INVISIBLE (1400 -550);
FORCEPROP 2 LAST CDS_LIB dev_discrete
J 0
(1350 -650);
PAINT ORANGE (1350 -650);
DISPLAY INVISIBLE (1350 -650);
FORCEPROP 0 LAST ROOM PVDDQ_DEF
J 0
(1400 -450);
DISPLAY 1.021277 (1400 -450);
PAINT ORANGE (1400 -450);
DISPLAY INVISIBLE (1400 -450);
FORCEPROP 2 LAST CDS_SEC 1
J 0
(1400 -450);
PAINT MONO (1400 -450);
DISPLAY INVISIBLE (1400 -450);
FORCEPROP 2 LAST $SEC 1
J 0
(1400 -450);
PAINT MONO (1400 -450);
DISPLAY INVISIBLE (1400 -450);
FORCEPROP 1 LAST PATH I224
J 0
(1400 -500);
DISPLAY 0.978723 (1400 -500);
PAINT WHITE (1400 -500);
DISPLAY INVISIBLE (1400 -500);
FORCEADD CAP_A..1
(1075 -650);
FORCEPROP 1 LAST PACK_TYPE 0603V
J 0
(1125 -850);
DISPLAY 0.617021 (1125 -850);
PAINT SKYBLUE (1125 -850);
FORCEPROP 1 LAST LOCATION C5M4
J 0
(1125 -550);
DISPLAY 0.617021 (1125 -550);
PAINT AQUA (1125 -550);
FORCEPROP 1 LAST TOLERANCE 20%
J 0
(1125 -700);
DISPLAY 0.617021 (1125 -700);
PAINT SKYBLUE (1125 -700);
FORCEPROP 1 LAST VOLTAGE 4V
J 0
(1125 -650);
DISPLAY 0.617021 (1125 -650);
PAINT SKYBLUE (1125 -650);
FORCEPROP 1 LAST MATERIAL X6S
J 0
(1125 -750);
DISPLAY 0.617021 (1125 -750);
PAINT SKYBLUE (1125 -750);
FORCEPROP 1 LAST VALUE 22.0UF
J 0
(1125 -600);
DISPLAY 0.617021 (1125 -600);
PAINT SKYBLUE (1125 -600);
FORCEPROP 1 LAST PART_NUMBER E15431-004
J 0
(1125 -800);
DISPLAY 0.617021 (1125 -800);
PAINT BLUE (1125 -800);
FORCEPROP 1 LASTPIN (1075 -750) $PN 2
J 0
(1085 -770);
DISPLAY 0.787234 (1085 -770);
PAINT ORANGE (1085 -770);
DISPLAY INVISIBLE (1085 -770);
FORCEPROP 1 LASTPIN (1075 -550) $PN 1
J 0
(1085 -570);
DISPLAY 0.787234 (1085 -570);
PAINT ORANGE (1085 -570);
DISPLAY INVISIBLE (1085 -570);
FORCEPROP 2 LAST CDS_LOCATION C5M4
J 0
(1125 -550);
DISPLAY 0.617021 (1125 -550);
PAINT AQUA (1125 -550);
DISPLAY INVISIBLE (1125 -550);
FORCEPROP 2 LAST CDS_LIB dev_discrete
J 0
(1075 -650);
PAINT ORANGE (1075 -650);
DISPLAY INVISIBLE (1075 -650);
FORCEPROP 1 LAST PATH I225
J 0
(1125 -500);
DISPLAY 0.978723 (1125 -500);
PAINT WHITE (1125 -500);
DISPLAY INVISIBLE (1125 -500);
FORCEPROP 2 LAST $SEC 1
J 0
(1125 -450);
PAINT MONO (1125 -450);
DISPLAY INVISIBLE (1125 -450);
FORCEPROP 2 LAST CDS_SEC 1
J 0
(1125 -450);
PAINT MONO (1125 -450);
DISPLAY INVISIBLE (1125 -450);
FORCEPROP 0 LAST ROOM PVDDQ_DEF
J 0
(1125 -450);
DISPLAY 1.021277 (1125 -450);
PAINT ORANGE (1125 -450);
DISPLAY INVISIBLE (1125 -450);
FORCEADD CAP_A..1
(800 -650);
FORCEPROP 1 LAST PACK_TYPE 0603V
J 0
(850 -850);
DISPLAY 0.617021 (850 -850);
PAINT SKYBLUE (850 -850);
FORCEPROP 1 LAST LOCATION C5M5
J 0
(850 -550);
DISPLAY 0.617021 (850 -550);
PAINT AQUA (850 -550);
FORCEPROP 1 LAST TOLERANCE 20%
J 0
(850 -700);
DISPLAY 0.617021 (850 -700);
PAINT SKYBLUE (850 -700);
FORCEPROP 1 LAST VOLTAGE 4V
J 0
(850 -650);
DISPLAY 0.617021 (850 -650);
PAINT SKYBLUE (850 -650);
FORCEPROP 1 LAST MATERIAL X6S
J 0
(850 -750);
DISPLAY 0.617021 (850 -750);
PAINT SKYBLUE (850 -750);
FORCEPROP 1 LAST VALUE 22.0UF
J 0
(850 -600);
DISPLAY 0.617021 (850 -600);
PAINT SKYBLUE (850 -600);
FORCEPROP 1 LAST PART_NUMBER E15431-004
J 0
(850 -800);
DISPLAY 0.617021 (850 -800);
PAINT BLUE (850 -800);
FORCEPROP 1 LASTPIN (800 -750) $PN 2
J 0
(810 -770);
DISPLAY 0.787234 (810 -770);
PAINT ORANGE (810 -770);
DISPLAY INVISIBLE (810 -770);
FORCEPROP 1 LASTPIN (800 -550) $PN 1
J 0
(810 -570);
DISPLAY 0.787234 (810 -570);
PAINT ORANGE (810 -570);
DISPLAY INVISIBLE (810 -570);
FORCEPROP 2 LAST CDS_LOCATION C5M5
J 0
(850 -550);
DISPLAY 0.617021 (850 -550);
PAINT AQUA (850 -550);
DISPLAY INVISIBLE (850 -550);
FORCEPROP 2 LAST CDS_LIB dev_discrete
J 0
(800 -650);
PAINT ORANGE (800 -650);
DISPLAY INVISIBLE (800 -650);
FORCEPROP 1 LAST PATH I226
J 0
(850 -500);
DISPLAY 0.978723 (850 -500);
PAINT WHITE (850 -500);
DISPLAY INVISIBLE (850 -500);
FORCEPROP 2 LAST $SEC 1
J 0
(850 -450);
PAINT MONO (850 -450);
DISPLAY INVISIBLE (850 -450);
FORCEPROP 2 LAST CDS_SEC 1
J 0
(850 -450);
PAINT MONO (850 -450);
DISPLAY INVISIBLE (850 -450);
FORCEPROP 0 LAST ROOM PVDDQ_DEF
J 0
(850 -450);
DISPLAY 1.021277 (850 -450);
PAINT ORANGE (850 -450);
DISPLAY INVISIBLE (850 -450);
FORCEADD CAP_A..1
(500 -650);
FORCEPROP 1 LAST MATERIAL X6S
J 0
(550 -750);
DISPLAY 0.617021 (550 -750);
PAINT SKYBLUE (550 -750);
FORCEPROP 1 LAST VOLTAGE 4V
J 0
(550 -650);
DISPLAY 0.617021 (550 -650);
PAINT SKYBLUE (550 -650);
FORCEPROP 1 LAST PACK_TYPE 0603V
J 0
(550 -850);
DISPLAY 0.617021 (550 -850);
PAINT SKYBLUE (550 -850);
FORCEPROP 1 LAST TOLERANCE 20%
J 0
(550 -700);
DISPLAY 0.617021 (550 -700);
PAINT SKYBLUE (550 -700);
FORCEPROP 1 LAST VALUE 22.0UF
J 0
(550 -600);
DISPLAY 0.617021 (550 -600);
PAINT SKYBLUE (550 -600);
FORCEPROP 1 LAST LOCATION C5M6
J 0
(550 -550);
DISPLAY 0.617021 (550 -550);
PAINT AQUA (550 -550);
FORCEPROP 1 LAST PART_NUMBER E15431-004
J 0
(550 -800);
DISPLAY 0.617021 (550 -800);
PAINT BLUE (550 -800);
FORCEPROP 2 LAST CDS_LIB dev_discrete
J 0
(500 -650);
PAINT ORANGE (500 -650);
DISPLAY INVISIBLE (500 -650);
FORCEPROP 1 LASTPIN (500 -750) $PN 2
J 0
(510 -770);
DISPLAY 0.787234 (510 -770);
PAINT ORANGE (510 -770);
DISPLAY INVISIBLE (510 -770);
FORCEPROP 1 LASTPIN (500 -550) $PN 1
J 0
(510 -570);
DISPLAY 0.787234 (510 -570);
PAINT ORANGE (510 -570);
DISPLAY INVISIBLE (510 -570);
FORCEPROP 2 LAST CDS_LOCATION C5M6
J 0
(550 -550);
DISPLAY 0.617021 (550 -550);
PAINT AQUA (550 -550);
DISPLAY INVISIBLE (550 -550);
FORCEPROP 0 LAST ROOM PVDDQ_DEF
J 0
(550 -450);
DISPLAY 1.021277 (550 -450);
PAINT ORANGE (550 -450);
DISPLAY INVISIBLE (550 -450);
FORCEPROP 2 LAST CDS_SEC 1
J 0
(550 -450);
PAINT MONO (550 -450);
DISPLAY INVISIBLE (550 -450);
FORCEPROP 2 LAST $SEC 1
J 0
(550 -450);
PAINT MONO (550 -450);
DISPLAY INVISIBLE (550 -450);
FORCEPROP 1 LAST PATH I227
J 0
(550 -500);
DISPLAY 0.978723 (550 -500);
PAINT WHITE (550 -500);
DISPLAY INVISIBLE (550 -500);
FORCEADD CAP_A..1
(200 -650);
FORCEPROP 1 LAST VOLTAGE 4V
J 0
(250 -650);
DISPLAY 0.617021 (250 -650);
PAINT SKYBLUE (250 -650);
FORCEPROP 1 LAST MATERIAL X6S
J 0
(250 -750);
DISPLAY 0.617021 (250 -750);
PAINT SKYBLUE (250 -750);
FORCEPROP 1 LAST PACK_TYPE 0603V
J 0
(250 -850);
DISPLAY 0.617021 (250 -850);
PAINT SKYBLUE (250 -850);
FORCEPROP 1 LAST TOLERANCE 20%
J 0
(250 -700);
DISPLAY 0.617021 (250 -700);
PAINT SKYBLUE (250 -700);
FORCEPROP 1 LAST VALUE 22.0UF
J 0
(250 -600);
DISPLAY 0.617021 (250 -600);
PAINT SKYBLUE (250 -600);
FORCEPROP 1 LAST LOCATION C5M7
J 0
(250 -550);
DISPLAY 0.617021 (250 -550);
PAINT AQUA (250 -550);
FORCEPROP 1 LAST PART_NUMBER E15431-004
J 0
(250 -800);
DISPLAY 0.617021 (250 -800);
PAINT BLUE (250 -800);
FORCEPROP 1 LASTPIN (200 -750) $PN 2
J 0
(210 -770);
DISPLAY 0.787234 (210 -770);
PAINT ORANGE (210 -770);
DISPLAY INVISIBLE (210 -770);
FORCEPROP 1 LASTPIN (200 -550) $PN 1
J 0
(210 -570);
DISPLAY 0.787234 (210 -570);
PAINT ORANGE (210 -570);
DISPLAY INVISIBLE (210 -570);
FORCEPROP 2 LAST CDS_LIB dev_discrete
J 0
(200 -650);
PAINT ORANGE (200 -650);
DISPLAY INVISIBLE (200 -650);
FORCEPROP 2 LAST CDS_LOCATION C5M7
J 0
(250 -550);
DISPLAY 0.617021 (250 -550);
PAINT AQUA (250 -550);
DISPLAY INVISIBLE (250 -550);
FORCEPROP 0 LAST ROOM PVDDQ_DEF
J 0
(250 -450);
DISPLAY 1.021277 (250 -450);
PAINT ORANGE (250 -450);
DISPLAY INVISIBLE (250 -450);
FORCEPROP 2 LAST CDS_SEC 1
J 0
(250 -450);
PAINT MONO (250 -450);
DISPLAY INVISIBLE (250 -450);
FORCEPROP 2 LAST $SEC 1
J 0
(250 -450);
PAINT MONO (250 -450);
DISPLAY INVISIBLE (250 -450);
FORCEPROP 1 LAST PATH I228
J 0
(250 -500);
DISPLAY 0.978723 (250 -500);
PAINT WHITE (250 -500);
DISPLAY INVISIBLE (250 -500);
FORCEADD CAP_A..1
(-125 -650);
FORCEPROP 1 LAST VOLTAGE 4V
J 0
(-75 -650);
DISPLAY 0.617021 (-75 -650);
PAINT SKYBLUE (-75 -650);
FORCEPROP 1 LAST MATERIAL X6S
J 0
(-75 -750);
DISPLAY 0.617021 (-75 -750);
PAINT SKYBLUE (-75 -750);
FORCEPROP 1 LAST PACK_TYPE 0603V
J 0
(-75 -850);
DISPLAY 0.617021 (-75 -850);
PAINT SKYBLUE (-75 -850);
FORCEPROP 1 LAST TOLERANCE 20%
J 0
(-75 -700);
DISPLAY 0.617021 (-75 -700);
PAINT SKYBLUE (-75 -700);
FORCEPROP 1 LAST VALUE 22.0UF
J 0
(-75 -600);
DISPLAY 0.617021 (-75 -600);
PAINT SKYBLUE (-75 -600);
FORCEPROP 1 LAST PART_NUMBER E15431-004
J 0
(-75 -800);
DISPLAY 0.617021 (-75 -800);
PAINT BLUE (-75 -800);
FORCEPROP 1 LAST LOCATION C5L13
J 0
(-75 -550);
DISPLAY 0.617021 (-75 -550);
PAINT AQUA (-75 -550);
FORCEPROP 1 LASTPIN (-125 -750) $PN 2
J 0
(-115 -770);
DISPLAY 0.787234 (-115 -770);
PAINT ORANGE (-115 -770);
DISPLAY INVISIBLE (-115 -770);
FORCEPROP 1 LASTPIN (-125 -550) $PN 1
J 0
(-115 -570);
DISPLAY 0.787234 (-115 -570);
PAINT ORANGE (-115 -570);
DISPLAY INVISIBLE (-115 -570);
FORCEPROP 2 LAST CDS_LOCATION C5L13
J 0
(-75 -550);
DISPLAY 0.617021 (-75 -550);
PAINT AQUA (-75 -550);
DISPLAY INVISIBLE (-75 -550);
FORCEPROP 2 LAST CDS_LIB dev_discrete
J 0
(-125 -650);
PAINT ORANGE (-125 -650);
DISPLAY INVISIBLE (-125 -650);
FORCEPROP 0 LAST ROOM PVDDQ_DEF
J 0
(-75 -450);
DISPLAY 1.021277 (-75 -450);
PAINT ORANGE (-75 -450);
DISPLAY INVISIBLE (-75 -450);
FORCEPROP 2 LAST CDS_SEC 1
J 0
(-75 -450);
PAINT MONO (-75 -450);
DISPLAY INVISIBLE (-75 -450);
FORCEPROP 2 LAST $SEC 1
J 0
(-75 -450);
PAINT MONO (-75 -450);
DISPLAY INVISIBLE (-75 -450);
FORCEPROP 1 LAST PATH I229
J 0
(-75 -500);
DISPLAY 0.978723 (-75 -500);
PAINT WHITE (-75 -500);
DISPLAY INVISIBLE (-75 -500);
FORCEADD CAP_A..1
(-400 -650);
FORCEPROP 1 LAST TOLERANCE 20%
J 0
(-350 -700);
DISPLAY 0.617021 (-350 -700);
PAINT SKYBLUE (-350 -700);
FORCEPROP 1 LAST VOLTAGE 4V
J 0
(-350 -650);
DISPLAY 0.617021 (-350 -650);
PAINT SKYBLUE (-350 -650);
FORCEPROP 1 LAST MATERIAL X6S
J 0
(-350 -750);
DISPLAY 0.617021 (-350 -750);
PAINT SKYBLUE (-350 -750);
FORCEPROP 1 LAST PACK_TYPE 0603V
J 0
(-350 -850);
DISPLAY 0.617021 (-350 -850);
PAINT SKYBLUE (-350 -850);
FORCEPROP 1 LAST VALUE 22.0UF
J 0
(-350 -600);
DISPLAY 0.617021 (-350 -600);
PAINT SKYBLUE (-350 -600);
FORCEPROP 1 LAST PART_NUMBER E15431-004
J 0
(-350 -800);
DISPLAY 0.617021 (-350 -800);
PAINT BLUE (-350 -800);
FORCEPROP 1 LAST LOCATION C5L12
J 0
(-350 -550);
DISPLAY 0.617021 (-350 -550);
PAINT AQUA (-350 -550);
FORCEPROP 1 LASTPIN (-400 -750) $PN 2
J 0
(-390 -770);
DISPLAY 0.787234 (-390 -770);
PAINT ORANGE (-390 -770);
DISPLAY INVISIBLE (-390 -770);
FORCEPROP 1 LASTPIN (-400 -550) $PN 1
J 0
(-390 -570);
DISPLAY 0.787234 (-390 -570);
PAINT ORANGE (-390 -570);
DISPLAY INVISIBLE (-390 -570);
FORCEPROP 2 LAST CDS_LOCATION C5L12
J 0
(-350 -550);
DISPLAY 0.617021 (-350 -550);
PAINT AQUA (-350 -550);
DISPLAY INVISIBLE (-350 -550);
FORCEPROP 2 LAST CDS_LIB dev_discrete
J 0
(-400 -650);
PAINT ORANGE (-400 -650);
DISPLAY INVISIBLE (-400 -650);
FORCEPROP 0 LAST ROOM PVDDQ_DEF
J 0
(-350 -450);
DISPLAY 1.021277 (-350 -450);
PAINT ORANGE (-350 -450);
DISPLAY INVISIBLE (-350 -450);
FORCEPROP 2 LAST CDS_SEC 1
J 0
(-350 -450);
PAINT MONO (-350 -450);
DISPLAY INVISIBLE (-350 -450);
FORCEPROP 2 LAST $SEC 1
J 0
(-350 -450);
PAINT MONO (-350 -450);
DISPLAY INVISIBLE (-350 -450);
FORCEPROP 1 LAST PATH I230
J 0
(-350 -500);
DISPLAY 0.978723 (-350 -500);
PAINT WHITE (-350 -500);
DISPLAY INVISIBLE (-350 -500);
FORCEADD CAP_A..1
(-700 -650);
FORCEPROP 1 LAST TOLERANCE 20%
J 0
(-650 -700);
DISPLAY 0.617021 (-650 -700);
PAINT SKYBLUE (-650 -700);
FORCEPROP 1 LAST VOLTAGE 4V
J 0
(-650 -650);
DISPLAY 0.617021 (-650 -650);
PAINT SKYBLUE (-650 -650);
FORCEPROP 1 LAST MATERIAL X6S
J 0
(-650 -750);
DISPLAY 0.617021 (-650 -750);
PAINT SKYBLUE (-650 -750);
FORCEPROP 1 LAST PACK_TYPE 0603V
J 0
(-650 -850);
DISPLAY 0.617021 (-650 -850);
PAINT SKYBLUE (-650 -850);
FORCEPROP 1 LAST VALUE 22.0UF
J 0
(-650 -600);
DISPLAY 0.617021 (-650 -600);
PAINT SKYBLUE (-650 -600);
FORCEPROP 1 LAST PART_NUMBER E15431-004
J 0
(-650 -800);
DISPLAY 0.617021 (-650 -800);
PAINT BLUE (-650 -800);
FORCEPROP 1 LAST LOCATION C5L11
J 0
(-650 -550);
DISPLAY 0.617021 (-650 -550);
PAINT AQUA (-650 -550);
FORCEPROP 1 LASTPIN (-700 -750) $PN 2
J 0
(-690 -770);
DISPLAY 0.787234 (-690 -770);
PAINT ORANGE (-690 -770);
DISPLAY INVISIBLE (-690 -770);
FORCEPROP 1 LASTPIN (-700 -550) $PN 1
J 0
(-690 -570);
DISPLAY 0.787234 (-690 -570);
PAINT ORANGE (-690 -570);
DISPLAY INVISIBLE (-690 -570);
FORCEPROP 2 LAST CDS_LOCATION C5L11
J 0
(-650 -550);
DISPLAY 0.617021 (-650 -550);
PAINT AQUA (-650 -550);
DISPLAY INVISIBLE (-650 -550);
FORCEPROP 2 LAST CDS_LIB dev_discrete
J 0
(-700 -650);
PAINT ORANGE (-700 -650);
DISPLAY INVISIBLE (-700 -650);
FORCEPROP 0 LAST ROOM PVDDQ_DEF
J 0
(-650 -450);
DISPLAY 1.021277 (-650 -450);
PAINT ORANGE (-650 -450);
DISPLAY INVISIBLE (-650 -450);
FORCEPROP 2 LAST CDS_SEC 1
J 0
(-650 -450);
PAINT MONO (-650 -450);
DISPLAY INVISIBLE (-650 -450);
FORCEPROP 2 LAST $SEC 1
J 0
(-650 -450);
PAINT MONO (-650 -450);
DISPLAY INVISIBLE (-650 -450);
FORCEPROP 1 LAST PATH I231
J 0
(-650 -500);
DISPLAY 0.978723 (-650 -500);
PAINT WHITE (-650 -500);
DISPLAY INVISIBLE (-650 -500);
FORCEADD CAP_A..1
(-1000 -650);
FORCEPROP 1 LAST PACK_TYPE 0603V
J 0
(-950 -850);
DISPLAY 0.617021 (-950 -850);
PAINT SKYBLUE (-950 -850);
FORCEPROP 1 LAST LOCATION C5L10
J 0
(-950 -550);
DISPLAY 0.617021 (-950 -550);
PAINT AQUA (-950 -550);
FORCEPROP 1 LAST VALUE 22.0UF
J 0
(-950 -600);
DISPLAY 0.617021 (-950 -600);
PAINT SKYBLUE (-950 -600);
FORCEPROP 1 LAST TOLERANCE 20%
J 0
(-950 -700);
DISPLAY 0.617021 (-950 -700);
PAINT SKYBLUE (-950 -700);
FORCEPROP 1 LAST MATERIAL X6S
J 0
(-950 -750);
DISPLAY 0.617021 (-950 -750);
PAINT SKYBLUE (-950 -750);
FORCEPROP 1 LAST VOLTAGE 4V
J 0
(-950 -650);
DISPLAY 0.617021 (-950 -650);
PAINT SKYBLUE (-950 -650);
FORCEPROP 1 LAST PART_NUMBER E15431-004
J 0
(-950 -800);
DISPLAY 0.617021 (-950 -800);
PAINT BLUE (-950 -800);
FORCEPROP 1 LASTPIN (-1000 -750) $PN 2
J 0
(-990 -770);
DISPLAY 0.787234 (-990 -770);
PAINT ORANGE (-990 -770);
DISPLAY INVISIBLE (-990 -770);
FORCEPROP 1 LASTPIN (-1000 -550) $PN 1
J 0
(-990 -570);
DISPLAY 0.787234 (-990 -570);
PAINT ORANGE (-990 -570);
DISPLAY INVISIBLE (-990 -570);
FORCEPROP 2 LAST CDS_LIB dev_discrete
J 0
(-1000 -650);
PAINT ORANGE (-1000 -650);
DISPLAY INVISIBLE (-1000 -650);
FORCEPROP 2 LAST CDS_LOCATION C5L10
J 0
(-950 -550);
DISPLAY 0.617021 (-950 -550);
PAINT AQUA (-950 -550);
DISPLAY INVISIBLE (-950 -550);
FORCEPROP 1 LAST PATH I232
J 0
(-950 -500);
DISPLAY 0.978723 (-950 -500);
PAINT WHITE (-950 -500);
DISPLAY INVISIBLE (-950 -500);
FORCEPROP 2 LAST $SEC 1
J 0
(-950 -450);
PAINT MONO (-950 -450);
DISPLAY INVISIBLE (-950 -450);
FORCEPROP 2 LAST CDS_SEC 1
J 0
(-950 -450);
PAINT MONO (-950 -450);
DISPLAY INVISIBLE (-950 -450);
FORCEPROP 0 LAST ROOM PVDDQ_DEF
J 0
(-950 -450);
DISPLAY 1.021277 (-950 -450);
PAINT ORANGE (-950 -450);
DISPLAY INVISIBLE (-950 -450);
FORCEADD CAP_A..1
(-1275 -650);
FORCEPROP 1 LAST PACK_TYPE 0603V
J 0
(-1225 -850);
DISPLAY 0.617021 (-1225 -850);
PAINT SKYBLUE (-1225 -850);
FORCEPROP 1 LAST LOCATION C5L9
J 0
(-1225 -550);
DISPLAY 0.617021 (-1225 -550);
PAINT AQUA (-1225 -550);
FORCEPROP 1 LAST VALUE 22.0UF
J 0
(-1225 -600);
DISPLAY 0.617021 (-1225 -600);
PAINT SKYBLUE (-1225 -600);
FORCEPROP 1 LAST TOLERANCE 20%
J 0
(-1225 -700);
DISPLAY 0.617021 (-1225 -700);
PAINT SKYBLUE (-1225 -700);
FORCEPROP 1 LAST VOLTAGE 4V
J 0
(-1225 -650);
DISPLAY 0.617021 (-1225 -650);
PAINT SKYBLUE (-1225 -650);
FORCEPROP 1 LAST MATERIAL X6S
J 0
(-1225 -750);
DISPLAY 0.617021 (-1225 -750);
PAINT SKYBLUE (-1225 -750);
FORCEPROP 1 LAST PART_NUMBER E15431-004
J 0
(-1225 -800);
DISPLAY 0.617021 (-1225 -800);
PAINT BLUE (-1225 -800);
FORCEPROP 1 LASTPIN (-1275 -750) $PN 2
J 0
(-1265 -770);
DISPLAY 0.787234 (-1265 -770);
PAINT ORANGE (-1265 -770);
DISPLAY INVISIBLE (-1265 -770);
FORCEPROP 1 LASTPIN (-1275 -550) $PN 1
J 0
(-1265 -570);
DISPLAY 0.787234 (-1265 -570);
PAINT ORANGE (-1265 -570);
DISPLAY INVISIBLE (-1265 -570);
FORCEPROP 2 LAST CDS_LOCATION C5L9
J 0
(-1225 -550);
DISPLAY 0.617021 (-1225 -550);
PAINT AQUA (-1225 -550);
DISPLAY INVISIBLE (-1225 -550);
FORCEPROP 2 LAST CDS_LIB dev_discrete
J 0
(-1275 -650);
PAINT ORANGE (-1275 -650);
DISPLAY INVISIBLE (-1275 -650);
FORCEPROP 0 LAST ROOM PVDDQ_DEF
J 0
(-1225 -450);
DISPLAY 1.021277 (-1225 -450);
PAINT ORANGE (-1225 -450);
DISPLAY INVISIBLE (-1225 -450);
FORCEPROP 2 LAST CDS_SEC 1
J 0
(-1225 -450);
PAINT MONO (-1225 -450);
DISPLAY INVISIBLE (-1225 -450);
FORCEPROP 2 LAST $SEC 1
J 0
(-1225 -450);
PAINT MONO (-1225 -450);
DISPLAY INVISIBLE (-1225 -450);
FORCEPROP 1 LAST PATH I233
J 0
(-1225 -500);
DISPLAY 0.978723 (-1225 -500);
PAINT WHITE (-1225 -500);
DISPLAY INVISIBLE (-1225 -500);
FORCEADD CAP_A..1
(-1550 -650);
FORCEPROP 1 LAST MATERIAL X6S
J 0
(-1500 -750);
DISPLAY 0.617021 (-1500 -750);
PAINT SKYBLUE (-1500 -750);
FORCEPROP 1 LAST VOLTAGE 4V
J 0
(-1500 -650);
DISPLAY 0.617021 (-1500 -650);
PAINT SKYBLUE (-1500 -650);
FORCEPROP 1 LAST PACK_TYPE 0603V
J 0
(-1500 -850);
DISPLAY 0.617021 (-1500 -850);
PAINT SKYBLUE (-1500 -850);
FORCEPROP 1 LAST TOLERANCE 20%
J 0
(-1500 -700);
DISPLAY 0.617021 (-1500 -700);
PAINT SKYBLUE (-1500 -700);
FORCEPROP 1 LAST VALUE 22.0UF
J 0
(-1500 -600);
DISPLAY 0.617021 (-1500 -600);
PAINT SKYBLUE (-1500 -600);
FORCEPROP 1 LAST LOCATION C5L8
J 0
(-1500 -550);
DISPLAY 0.617021 (-1500 -550);
PAINT AQUA (-1500 -550);
FORCEPROP 1 LAST PART_NUMBER E15431-004
J 0
(-1500 -800);
DISPLAY 0.617021 (-1500 -800);
PAINT BLUE (-1500 -800);
FORCEPROP 1 LASTPIN (-1550 -750) $PN 2
J 0
(-1540 -770);
DISPLAY 0.787234 (-1540 -770);
PAINT ORANGE (-1540 -770);
DISPLAY INVISIBLE (-1540 -770);
FORCEPROP 1 LASTPIN (-1550 -550) $PN 1
J 0
(-1540 -570);
DISPLAY 0.787234 (-1540 -570);
PAINT ORANGE (-1540 -570);
DISPLAY INVISIBLE (-1540 -570);
FORCEPROP 2 LAST CDS_LIB dev_discrete
J 0
(-1550 -650);
PAINT ORANGE (-1550 -650);
DISPLAY INVISIBLE (-1550 -650);
FORCEPROP 2 LAST CDS_LOCATION C5L8
J 0
(-1500 -550);
DISPLAY 0.617021 (-1500 -550);
PAINT AQUA (-1500 -550);
DISPLAY INVISIBLE (-1500 -550);
FORCEPROP 0 LAST ROOM PVDDQ_DEF
J 0
(-1500 -450);
DISPLAY 1.021277 (-1500 -450);
PAINT ORANGE (-1500 -450);
DISPLAY INVISIBLE (-1500 -450);
FORCEPROP 2 LAST CDS_SEC 1
J 0
(-1500 -450);
PAINT MONO (-1500 -450);
DISPLAY INVISIBLE (-1500 -450);
FORCEPROP 2 LAST $SEC 1
J 0
(-1500 -450);
PAINT MONO (-1500 -450);
DISPLAY INVISIBLE (-1500 -450);
FORCEPROP 1 LAST PATH I234
J 0
(-1500 -500);
DISPLAY 0.978723 (-1500 -500);
PAINT WHITE (-1500 -500);
DISPLAY INVISIBLE (-1500 -500);
FORCEADD PVDDQ_DEF..1
(-2150 -400);
FORCEPROP 3 LASTPIN (-2150 -450) SIG_NAME PVDDQ_DEF\g
J 0
(-2140 -440);
DISPLAY 0.659574 (-2140 -440);
PAINT MONO (-2140 -440);
DISPLAY INVISIBLE (-2140 -440);
FORCEPROP 1 LAST VOLTAGE 1.2V
J 0
(-2195 -443);
DISPLAY 0.340426 (-2195 -443);
PAINT SKYBLUE (-2195 -443);
DISPLAY INVISIBLE (-2195 -443);
FORCEPROP 1 LAST BODY_TYPE PLUMBING
J 0
(-2195 -443);
DISPLAY 0.340426 (-2195 -443);
PAINT GREEN (-2195 -443);
DISPLAY INVISIBLE (-2195 -443);
FORCEPROP 2 LAST CDS_LIB mstr_symbols
J 0
(-2150 -400);
PAINT ORANGE (-2150 -400);
DISPLAY INVISIBLE (-2150 -400);
FORCEPROP 1 LAST PATH I235
J 0
(-2100 -375);
DISPLAY 0.872340 (-2100 -375);
PAINT AQUA (-2100 -375);
DISPLAY INVISIBLE (-2100 -375);
FORCEPROP 1 LAST HDL_POWER PVDDQ_DEF
J 1
(-2150 -350);
DISPLAY 0.872340 (-2150 -350);
PAINT GREEN (-2150 -350);
DISPLAY INVISIBLE (-2150 -350);
FORCEPROP 2 LAST BOM_COST PROC_SOCKET 
J 0
(-2150 -300);
DISPLAY 1.446809 (-2150 -300);
PAINT MONO (-2150 -300);
DISPLAY INVISIBLE (-2150 -300);
FORCEPROP 2 LAST ROOM VDDQ_DEF_PWR_VR
J 0
(-2150 -300);
DISPLAY 1.936170 (-2150 -300);
PAINT ORANGE (-2150 -300);
DISPLAY INVISIBLE (-2150 -300);
FORCEADD CAP_A..1
(-1850 -650);
FORCEPROP 1 LAST VOLTAGE 4V
J 0
(-1800 -650);
DISPLAY 0.617021 (-1800 -650);
PAINT SKYBLUE (-1800 -650);
FORCEPROP 1 LAST MATERIAL X6S
J 0
(-1800 -750);
DISPLAY 0.617021 (-1800 -750);
PAINT SKYBLUE (-1800 -750);
FORCEPROP 1 LAST PACK_TYPE 0603V
J 0
(-1800 -850);
DISPLAY 0.617021 (-1800 -850);
PAINT SKYBLUE (-1800 -850);
FORCEPROP 1 LAST TOLERANCE 20%
J 0
(-1800 -700);
DISPLAY 0.617021 (-1800 -700);
PAINT SKYBLUE (-1800 -700);
FORCEPROP 1 LAST VALUE 22.0UF
J 0
(-1800 -600);
DISPLAY 0.617021 (-1800 -600);
PAINT SKYBLUE (-1800 -600);
FORCEPROP 1 LAST LOCATION C5L7
J 0
(-1800 -550);
DISPLAY 0.617021 (-1800 -550);
PAINT AQUA (-1800 -550);
FORCEPROP 1 LAST PART_NUMBER E15431-004
J 0
(-1800 -800);
DISPLAY 0.617021 (-1800 -800);
PAINT BLUE (-1800 -800);
FORCEPROP 1 LASTPIN (-1850 -750) $PN 2
J 0
(-1840 -770);
DISPLAY 0.787234 (-1840 -770);
PAINT ORANGE (-1840 -770);
DISPLAY INVISIBLE (-1840 -770);
FORCEPROP 1 LASTPIN (-1850 -550) $PN 1
J 0
(-1840 -570);
DISPLAY 0.787234 (-1840 -570);
PAINT ORANGE (-1840 -570);
DISPLAY INVISIBLE (-1840 -570);
FORCEPROP 2 LAST CDS_LIB dev_discrete
J 0
(-1850 -650);
PAINT ORANGE (-1850 -650);
DISPLAY INVISIBLE (-1850 -650);
FORCEPROP 2 LAST CDS_LOCATION C5L7
J 0
(-1800 -550);
DISPLAY 0.617021 (-1800 -550);
PAINT AQUA (-1800 -550);
DISPLAY INVISIBLE (-1800 -550);
FORCEPROP 0 LAST ROOM PVDDQ_DEF
J 0
(-1800 -450);
DISPLAY 1.021277 (-1800 -450);
PAINT ORANGE (-1800 -450);
DISPLAY INVISIBLE (-1800 -450);
FORCEPROP 2 LAST CDS_SEC 1
J 0
(-1800 -450);
PAINT MONO (-1800 -450);
DISPLAY INVISIBLE (-1800 -450);
FORCEPROP 2 LAST $SEC 1
J 0
(-1800 -450);
PAINT MONO (-1800 -450);
DISPLAY INVISIBLE (-1800 -450);
FORCEPROP 1 LAST PATH I236
J 0
(-1800 -500);
DISPLAY 0.978723 (-1800 -500);
PAINT WHITE (-1800 -500);
DISPLAY INVISIBLE (-1800 -500);
FORCEADD CAP_A..1
(-2150 -650);
FORCEPROP 1 LAST MATERIAL X6S
J 0
(-2100 -750);
DISPLAY 0.617021 (-2100 -750);
PAINT SKYBLUE (-2100 -750);
FORCEPROP 1 LAST VOLTAGE 4V
J 0
(-2100 -650);
DISPLAY 0.617021 (-2100 -650);
PAINT SKYBLUE (-2100 -650);
FORCEPROP 1 LAST PACK_TYPE 0603V
J 0
(-2100 -850);
DISPLAY 0.617021 (-2100 -850);
PAINT SKYBLUE (-2100 -850);
FORCEPROP 1 LAST TOLERANCE 20%
J 0
(-2100 -700);
DISPLAY 0.617021 (-2100 -700);
PAINT SKYBLUE (-2100 -700);
FORCEPROP 1 LAST VALUE 22.0UF
J 0
(-2100 -600);
DISPLAY 0.617021 (-2100 -600);
PAINT SKYBLUE (-2100 -600);
FORCEPROP 1 LAST PART_NUMBER E15431-004
J 0
(-2100 -800);
DISPLAY 0.617021 (-2100 -800);
PAINT BLUE (-2100 -800);
FORCEPROP 1 LAST LOCATION C5L6
J 0
(-2100 -550);
DISPLAY 0.617021 (-2100 -550);
PAINT AQUA (-2100 -550);
FORCEPROP 1 LASTPIN (-2150 -750) $PN 2
J 0
(-2140 -770);
DISPLAY 0.787234 (-2140 -770);
PAINT ORANGE (-2140 -770);
DISPLAY INVISIBLE (-2140 -770);
FORCEPROP 2 LAST CDS_LIB dev_discrete
J 0
(-2150 -650);
PAINT ORANGE (-2150 -650);
DISPLAY INVISIBLE (-2150 -650);
FORCEPROP 2 LAST CDS_LOCATION C5L6
J 0
(-2100 -550);
DISPLAY 0.617021 (-2100 -550);
PAINT AQUA (-2100 -550);
DISPLAY INVISIBLE (-2100 -550);
FORCEPROP 1 LASTPIN (-2150 -550) $PN 1
J 0
(-2140 -570);
DISPLAY 0.787234 (-2140 -570);
PAINT ORANGE (-2140 -570);
DISPLAY INVISIBLE (-2140 -570);
FORCEPROP 1 LAST PATH I237
J 0
(-2100 -500);
DISPLAY 0.978723 (-2100 -500);
PAINT WHITE (-2100 -500);
DISPLAY INVISIBLE (-2100 -500);
FORCEPROP 2 LAST $SEC 1
J 0
(-2100 -450);
PAINT MONO (-2100 -450);
DISPLAY INVISIBLE (-2100 -450);
FORCEPROP 2 LAST CDS_SEC 1
J 0
(-2100 -450);
PAINT MONO (-2100 -450);
DISPLAY INVISIBLE (-2100 -450);
FORCEPROP 0 LAST ROOM PVDDQ_DEF
J 0
(-2100 -450);
DISPLAY 1.021277 (-2100 -450);
PAINT ORANGE (-2100 -450);
DISPLAY INVISIBLE (-2100 -450);
FORCEADD GND..1
(-2150 -925);
FORCEPROP 3 LASTPIN (-2150 -875) SIG_NAME GND\g
J 0
(-2140 -865);
DISPLAY 0.659574 (-2140 -865);
PAINT MONO (-2140 -865);
DISPLAY INVISIBLE (-2140 -865);
FORCEPROP 2 LAST ROOM VDDQ_ABC_PWR_VR
J 0
(-2700 -850);
DISPLAY 1.936170 (-2700 -850);
PAINT ORANGE (-2700 -850);
DISPLAY INVISIBLE (-2700 -850);
FORCEPROP 2 LAST BOM_COST PROC_VRD_VCCIN_CPU0
J 0
(-2525 -850);
DISPLAY 1.446809 (-2525 -850);
PAINT MONO (-2525 -850);
DISPLAY INVISIBLE (-2525 -850);
FORCEPROP 1 LAST BODY_TYPE PLUMBING
J 0
(-2195 -968);
DISPLAY 0.340426 (-2195 -968);
PAINT GREEN (-2195 -968);
DISPLAY INVISIBLE (-2195 -968);
FORCEPROP 1 LAST SIZE 1B
J 0
(-2075 -975);
DISPLAY 1.723404 (-2075 -975);
PAINT GREEN (-2075 -975);
DISPLAY INVISIBLE (-2075 -975);
FORCEPROP 1 LAST PATH I238
J 0
(-2075 -925);
DISPLAY 0.872340 (-2075 -925);
PAINT AQUA (-2075 -925);
DISPLAY INVISIBLE (-2075 -925);
FORCEPROP 2 LAST CDS_LIB mstr_symbols
J 0
(-2150 -925);
PAINT ORANGE (-2150 -925);
DISPLAY INVISIBLE (-2150 -925);
FORCEPROP 1 LAST VOLTAGE 0
J 0
(-2150 -925);
PAINT SKYBLUE (-2150 -925);
DISPLAY INVISIBLE (-2150 -925);
FORCEPROP 1 LAST HDL_POWER GND
J 0
(-2150 -775);
DISPLAY 1.723404 (-2150 -775);
PAINT GREEN (-2150 -775);
DISPLAY INVISIBLE (-2150 -775);
FORCEADD SHUNT..1
(-300 2075);
FORCEPROP 1 LAST PART_NUMBER N_A
J 0
(-375 1985);
DISPLAY 0.617021 (-375 1985);
PAINT BLUE (-375 1985);
FORCEPROP 1 LASTPIN (-450 2075) $PN 1
J 2
(-400 2085);
DISPLAY 0.617021 (-400 2085);
PAINT ORANGE (-400 2085);
FORCEPROP 1 LAST LOCATION SH4L2
J 0
(-375 2125);
DISPLAY 0.617021 (-375 2125);
PAINT AQUA (-375 2125);
FORCEPROP 1 LASTPIN (-150 2075) $PN 2
J 0
(-190 2085);
DISPLAY 0.617021 (-190 2085);
PAINT ORANGE (-190 2085);
FORCEPROP 1 LAST PIN_SHORT A:B
J 0
(-375 1825);
DISPLAY 1.021277 (-375 1825);
PAINT ORANGE (-375 1825);
DISPLAY INVISIBLE (-375 1825);
FORCEPROP 1 LAST PACK_TYPE SH0201
J 0
(-360 1890);
DISPLAY 0.978723 (-360 1890);
PAINT SKYBLUE (-360 1890);
DISPLAY INVISIBLE (-360 1890);
FORCEPROP 1 LAST MATERIAL EMPTY
J 0
(-375 1940);
DISPLAY 0.978723 (-375 1940);
PAINT RED (-375 1940);
DISPLAY INVISIBLE (-375 1940);
FORCEPROP 2 LAST CDS_LIB mstr_misc
J 0
(-300 2075);
PAINT ORANGE (-300 2075);
DISPLAY INVISIBLE (-300 2075);
FORCEPROP 0 LAST SEC 1
J 0
(-375 2175);
DISPLAY 0.680851 (-375 2175);
PAINT MONO (-375 2175);
DISPLAY INVISIBLE (-375 2175);
FORCEPROP 1 LAST PATH I239
J 0
(-350 2175);
DISPLAY 0.978723 (-350 2175);
PAINT ORANGE (-350 2175);
DISPLAY INVISIBLE (-350 2175);
FORCEPROP 2 LAST SEC_TYPE SH0201
J 0
(-350 2225);
DISPLAY 1.021277 (-350 2225);
PAINT ORANGE (-350 2225);
DISPLAY INVISIBLE (-350 2225);
FORCEADD SHUNT..1
(-325 1625);
FORCEPROP 1 LAST PART_NUMBER N_A
J 0
(-400 1535);
DISPLAY 0.617021 (-400 1535);
PAINT BLUE (-400 1535);
FORCEPROP 1 LASTPIN (-475 1625) $PN 1
J 2
(-425 1635);
DISPLAY 0.617021 (-425 1635);
PAINT ORANGE (-425 1635);
FORCEPROP 1 LAST LOCATION SH4L1
J 0
(-400 1675);
DISPLAY 0.617021 (-400 1675);
PAINT AQUA (-400 1675);
FORCEPROP 1 LASTPIN (-175 1625) $PN 2
J 0
(-215 1635);
DISPLAY 0.617021 (-215 1635);
PAINT ORANGE (-215 1635);
FORCEPROP 1 LAST PIN_SHORT A:B
J 0
(-400 1375);
DISPLAY 1.021277 (-400 1375);
PAINT ORANGE (-400 1375);
DISPLAY INVISIBLE (-400 1375);
FORCEPROP 1 LAST PACK_TYPE SH0201
J 0
(-385 1440);
DISPLAY 0.978723 (-385 1440);
PAINT SKYBLUE (-385 1440);
DISPLAY INVISIBLE (-385 1440);
FORCEPROP 1 LAST MATERIAL EMPTY
J 0
(-400 1490);
DISPLAY 0.978723 (-400 1490);
PAINT RED (-400 1490);
DISPLAY INVISIBLE (-400 1490);
FORCEPROP 0 LAST SEC 1
J 0
(-400 1725);
DISPLAY 0.680851 (-400 1725);
PAINT MONO (-400 1725);
DISPLAY INVISIBLE (-400 1725);
FORCEPROP 2 LAST CDS_LIB mstr_misc
J 0
(-325 1625);
PAINT ORANGE (-325 1625);
DISPLAY INVISIBLE (-325 1625);
FORCEPROP 1 LAST PATH I240
J 0
(-375 1725);
DISPLAY 0.978723 (-375 1725);
PAINT ORANGE (-375 1725);
DISPLAY INVISIBLE (-375 1725);
FORCEPROP 2 LAST SEC_TYPE SH0201
J 0
(-375 1775);
DISPLAY 1.021277 (-375 1775);
PAINT ORANGE (-375 1775);
DISPLAY INVISIBLE (-375 1775);
FORCEADD RES..2
(4550 -175);
FORCEPROP 1 LASTPIN (4550 -275) $PN 2
J 0
(4555 -265);
DISPLAY 0.617021 (4555 -265);
PAINT GREEN (4555 -265);
FORCEPROP 1 LASTPIN (4550 -75) $PN 1
J 0
(4555 -113);
DISPLAY 0.617021 (4555 -113);
PAINT GREEN (4555 -113);
FORCEPROP 1 LAST WATTAGE 1/10W
J 0
(4590 -200);
DISPLAY 0.617021 (4590 -200);
PAINT SKYBLUE (4590 -200);
FORCEPROP 1 LAST MATERIAL CHIP
J 0
(4590 -250);
DISPLAY 0.617021 (4590 -250);
PAINT SKYBLUE (4590 -250);
FORCEPROP 1 LAST PACK_TYPE 0603
J 0
(4590 -350);
DISPLAY 0.617021 (4590 -350);
PAINT SKYBLUE (4590 -350);
FORCEPROP 1 LAST TOLERANCE 1%
J 0
(4595 -150);
DISPLAY 0.617021 (4595 -150);
PAINT SKYBLUE (4595 -150);
FORCEPROP 1 LAST VALUE 120.0
J 0
(4595 -100);
DISPLAY 0.617021 (4595 -100);
PAINT SKYBLUE (4595 -100);
FORCEPROP 1 LAST PART_NUMBER G22026-003
J 0
(4590 -300);
DISPLAY 0.617021 (4590 -300);
PAINT BLUE (4590 -300);
FORCEPROP 1 LAST LOCATION R4L4
J 0
(4595 -50);
DISPLAY 0.617021 (4595 -50);
PAINT AQUA (4595 -50);
FORCEPROP 2 LAST CDS_LIB mstr_discrete
J 0
(4550 -175);
PAINT ORANGE (4550 -175);
DISPLAY INVISIBLE (4550 -175);
FORCEPROP 2 LAST CDS_LOCATION R4L4
J 0
(4595 -50);
DISPLAY 0.617021 (4595 -50);
PAINT AQUA (4595 -50);
DISPLAY INVISIBLE (4595 -50);
FORCEPROP 1 LAST PATH I58
J 0
(4600 0);
DISPLAY 0.978723 (4600 0);
PAINT GREEN (4600 0);
DISPLAY INVISIBLE (4600 0);
FORCEPROP 2 LAST BOM_COST MEM_VRD_PVPP_DEF
J 0
(4600 0);
PAINT MONO (4600 0);
DISPLAY INVISIBLE (4600 0);
FORCEPROP 2 LAST ROOM VDDQ_DEF_PWR_VR
J 0
(4600 0);
PAINT MONO (4600 0);
DISPLAY INVISIBLE (4600 0);
FORCEPROP 2 LAST $SEC 1
J 0
(4600 50);
PAINT MONO (4600 50);
DISPLAY INVISIBLE (4600 50);
FORCEPROP 2 LAST CDS_SEC 1
J 0
(4600 50);
PAINT MONO (4600 50);
DISPLAY INVISIBLE (4600 50);
FORCEADD GND..1
(-50 1400);
FORCEPROP 3 LASTPIN (-50 1450) SIG_NAME GND\g
J 0
(-40 1460);
DISPLAY 0.659574 (-40 1460);
PAINT MONO (-40 1460);
DISPLAY INVISIBLE (-40 1460);
FORCEPROP 2 LAST ROOM VDDQ_DEF_PWR_VR
J 0
(-600 1475);
PAINT ORANGE (-600 1475);
DISPLAY INVISIBLE (-600 1475);
FORCEPROP 2 LAST BOM_COST MEM_VRD_PVPP_DEF
J 0
(-375 1475);
PAINT MONO (-375 1475);
DISPLAY INVISIBLE (-375 1475);
FORCEPROP 1 LAST BODY_TYPE PLUMBING
J 0
(-95 1357);
DISPLAY 0.340426 (-95 1357);
PAINT GREEN (-95 1357);
DISPLAY INVISIBLE (-95 1357);
FORCEPROP 2 LAST CDS_LIB mstr_symbols
J 0
(-50 1400);
PAINT ORANGE (-50 1400);
DISPLAY INVISIBLE (-50 1400);
FORCEPROP 1 LAST VOLTAGE 0
J 0
(-50 1400);
PAINT SKYBLUE (-50 1400);
DISPLAY INVISIBLE (-50 1400);
FORCEPROP 1 LAST HDL_POWER GND
J 0
(-50 1550);
DISPLAY 0.893617 (-50 1550);
PAINT GREEN (-50 1550);
DISPLAY INVISIBLE (-50 1550);
FORCEPROP 1 LAST PATH I65
J 0
(25 1400);
DISPLAY 1.170213 (25 1400);
PAINT AQUA (25 1400);
DISPLAY INVISIBLE (25 1400);
FORCEPROP 1 LAST SIZE 1B
J 0
(25 1350);
DISPLAY 0.893617 (25 1350);
PAINT GREEN (25 1350);
DISPLAY INVISIBLE (25 1350);
FORCEADD OFFPAGE..1
(-1975 1800);
FORCEPROP 2 LAST $XR0 218 
J 0
(-2257 1800);
DISPLAY 0.638298 (-2257 1800);
PAINT MONO (-2257 1800);
FORCEPROP 2 LAST PATH I70
J 0
(-1905 1870);
DISPLAY 1.361702 (-1905 1870);
PAINT ORANGE (-1905 1870);
DISPLAY INVISIBLE (-1905 1870);
FORCEPROP 1 LAST COMMENT_BODY TRUE
J 0
(-1850 1700);
DISPLAY 0.893617 (-1850 1700);
PAINT GREEN (-1850 1700);
DISPLAY INVISIBLE (-1850 1700);
FORCEPROP 2 LAST CDS_LIB mstr_standard
J 0
(-1975 1800);
PAINT ORANGE (-1975 1800);
DISPLAY INVISIBLE (-1975 1800);
FORCEPROP 1 LAST OFFPAGE TRUE
J 0
(-1650 1675);
DISPLAY 0.893617 (-1650 1675);
PAINT GREEN (-1650 1675);
DISPLAY INVISIBLE (-1650 1675);
FORCEADD OFFPAGE..1
(-1975 2050);
FORCEPROP 2 LAST $XR0 218 
J 0
(-2257 2050);
DISPLAY 0.638298 (-2257 2050);
PAINT MONO (-2257 2050);
FORCEPROP 1 LAST COMMENT_BODY TRUE
J 0
(-1850 1950);
DISPLAY 1.170213 (-1850 1950);
PAINT GREEN (-1850 1950);
DISPLAY INVISIBLE (-1850 1950);
FORCEPROP 1 LAST OFFPAGE TRUE
J 0
(-1650 1925);
DISPLAY 1.170213 (-1650 1925);
PAINT GREEN (-1650 1925);
DISPLAY INVISIBLE (-1650 1925);
FORCEPROP 2 LAST CDS_LIB mstr_standard
J 0
(-1975 2050);
PAINT ORANGE (-1975 2050);
DISPLAY INVISIBLE (-1975 2050);
FORCEPROP 2 LAST PATH I72
J 0
(-1925 2125);
DISPLAY 1.361702 (-1925 2125);
PAINT ORANGE (-1925 2125);
DISPLAY INVISIBLE (-1925 2125);
FORCEADD PVDDQ_DEF..1
(-25 2275);
FORCEPROP 3 LASTPIN (-25 2225) SIG_NAME PVDDQ_DEF\g
J 0
(-15 2235);
DISPLAY 0.659574 (-15 2235);
PAINT MONO (-15 2235);
DISPLAY INVISIBLE (-15 2235);
FORCEPROP 1 LAST BODY_TYPE PLUMBING
J 0
(-70 2232);
DISPLAY 0.340426 (-70 2232);
PAINT GREEN (-70 2232);
DISPLAY INVISIBLE (-70 2232);
FORCEPROP 1 LAST VOLTAGE 1.2V
J 0
(-70 2232);
DISPLAY 0.340426 (-70 2232);
PAINT SKYBLUE (-70 2232);
DISPLAY INVISIBLE (-70 2232);
FORCEPROP 2 LAST CDS_LIB mstr_symbols
J 0
(-25 2275);
PAINT ORANGE (-25 2275);
DISPLAY INVISIBLE (-25 2275);
FORCEPROP 1 LAST HDL_POWER PVDDQ_DEF
J 1
(-25 2325);
DISPLAY 0.872340 (-25 2325);
PAINT GREEN (-25 2325);
DISPLAY INVISIBLE (-25 2325);
FORCEPROP 2 LAST BOM_COST MEM_VRD_PVPP_DEF
J 0
(0 2375);
PAINT MONO (0 2375);
DISPLAY INVISIBLE (0 2375);
FORCEPROP 1 LAST PATH I73
J 0
(25 2300);
DISPLAY 0.872340 (25 2300);
PAINT AQUA (25 2300);
DISPLAY INVISIBLE (25 2300);
FORCEPROP 2 LAST ROOM VDDQ_DEF_PWR_VR
J 0
(225 2375);
PAINT ORANGE (225 2375);
DISPLAY INVISIBLE (225 2375);
FORCEADD RES..2
(-700 1825);
FORCEPROP 1 LASTPIN (-700 1725) $PN 2
J 0
(-695 1735);
DISPLAY 0.617021 (-695 1735);
PAINT ORANGE (-695 1735);
FORCEPROP 1 LAST PACK_TYPE 0402
J 0
(-660 1650);
DISPLAY 0.617021 (-660 1650);
PAINT SKYBLUE (-660 1650);
FORCEPROP 1 LAST MATERIAL EMPTY
J 0
(-660 1750);
DISPLAY 0.617021 (-660 1750);
PAINT RED (-660 1750);
FORCEPROP 1 LASTPIN (-700 1925) $PN 1
J 0
(-695 1887);
DISPLAY 0.617021 (-695 1887);
PAINT ORANGE (-695 1887);
FORCEPROP 1 LAST WATTAGE 1/16W
J 0
(-660 1800);
DISPLAY 0.617021 (-660 1800);
PAINT SKYBLUE (-660 1800);
FORCEPROP 1 LAST TOLERANCE 1%
J 0
(-655 1850);
DISPLAY 0.617021 (-655 1850);
PAINT SKYBLUE (-655 1850);
FORCEPROP 1 LAST LOCATION R4L2
J 0
(-655 1950);
DISPLAY 0.617021 (-655 1950);
PAINT AQUA (-655 1950);
FORCEPROP 1 LAST VALUE 100.0
J 0
(-655 1900);
DISPLAY 0.617021 (-655 1900);
PAINT SKYBLUE (-655 1900);
FORCEPROP 1 LAST PART_NUMBER G21796-017
J 0
(-660 1700);
DISPLAY 0.617021 (-660 1700);
PAINT BLUE (-660 1700);
FORCEPROP 2 LAST CDS_LIB mstr_discrete
J 0
(-700 1825);
PAINT ORANGE (-700 1825);
DISPLAY INVISIBLE (-700 1825);
FORCEPROP 2 LAST CDS_LOCATION R4L2
J 0
(-655 1950);
DISPLAY 0.617021 (-655 1950);
PAINT AQUA (-655 1950);
DISPLAY INVISIBLE (-655 1950);
FORCEPROP 0 LAST ROOM VDDQ_DEF_PWR_VR
J 0
(-650 2000);
DISPLAY 1.021277 (-650 2000);
PAINT ORANGE (-650 2000);
DISPLAY INVISIBLE (-650 2000);
FORCEPROP 1 LAST PATH I74
J 0
(-650 2000);
DISPLAY 1.319149 (-650 2000);
PAINT WHITE (-650 2000);
DISPLAY INVISIBLE (-650 2000);
FORCEPROP 2 LAST SEC_TYPE 0402
J 0
(-650 2075);
DISPLAY 1.021277 (-650 2075);
PAINT ORANGE (-650 2075);
DISPLAY INVISIBLE (-650 2075);
FORCEPROP 2 LAST SEC 1
J 0
(-650 2075);
DISPLAY 0.680851 (-650 2075);
PAINT MONO (-650 2075);
DISPLAY INVISIBLE (-650 2075);
FORCEADD CAPP..1
(2925 -150);
FORCEPROP 1 LASTPIN (2925 -250) $PN 2
J 0
(2935 -265);
DISPLAY 0.617021 (2935 -265);
PAINT ORANGE (2935 -265);
FORCEPROP 1 LASTPIN (2925 -50) $PN 1
J 0
(2935 -65);
DISPLAY 0.617021 (2935 -65);
PAINT ORANGE (2935 -65);
FORCEPROP 1 LAST TOLERANCE 20%
J 0
(2975 -150);
DISPLAY 0.617021 (2975 -150);
PAINT SKYBLUE (2975 -150);
FORCEPROP 1 LAST MATERIAL ALUM
J 0
(2975 -250);
DISPLAY 0.617021 (2975 -250);
PAINT SKYBLUE (2975 -250);
FORCEPROP 1 LAST VOLTAGE 2.5V
J 0
(2975 -200);
DISPLAY 0.617021 (2975 -200);
PAINT SKYBLUE (2975 -200);
FORCEPROP 1 LAST PACK_TYPE 3018
J 0
(2975 -300);
DISPLAY 0.617021 (2975 -300);
PAINT SKYBLUE (2975 -300);
FORCEPROP 1 LAST VALUE 470UF
J 0
(2975 -100);
DISPLAY 0.617021 (2975 -100);
PAINT SKYBLUE (2975 -100);
FORCEPROP 1 LAST PART_NUMBER 699013-049
J 0
(2975 -350);
DISPLAY 0.617021 (2975 -350);
PAINT BLUE (2975 -350);
FORCEPROP 1 LAST LOCATION C3L6
J 0
(2975 -50);
DISPLAY 0.617021 (2975 -50);
PAINT AQUA (2975 -50);
FORCEPROP 2 LAST CDS_LIB mstr_discrete
J 0
(2925 -150);
PAINT ORANGE (2925 -150);
DISPLAY INVISIBLE (2925 -150);
FORCEPROP 2 LAST CDS_LOCATION C3L6
J 0
(2975 -50);
DISPLAY 0.617021 (2975 -50);
PAINT AQUA (2975 -50);
DISPLAY INVISIBLE (2975 -50);
FORCEPROP 1 LAST PATH I75
J 0
(2975 0);
DISPLAY 1.319149 (2975 0);
PAINT ORANGE (2975 0);
DISPLAY INVISIBLE (2975 0);
FORCEPROP 0 LAST ROOM VDDQ_DEF_PWR_VR
J 0
(2975 0);
DISPLAY 1.021277 (2975 0);
PAINT ORANGE (2975 0);
DISPLAY INVISIBLE (2975 0);
FORCEPROP 2 LAST SEC_TYPE 3018
J 0
(2975 75);
DISPLAY 1.021277 (2975 75);
PAINT ORANGE (2975 75);
DISPLAY INVISIBLE (2975 75);
FORCEPROP 2 LAST SEC 1
J 0
(2975 75);
DISPLAY 0.680851 (2975 75);
PAINT MONO (2975 75);
DISPLAY INVISIBLE (2975 75);
FORCEADD CAPP..1
(3350 -150);
FORCEPROP 1 LAST PACK_TYPE 3018
J 0
(3400 -300);
DISPLAY 0.617021 (3400 -300);
PAINT SKYBLUE (3400 -300);
FORCEPROP 1 LASTPIN (3350 -250) $PN 2
J 0
(3360 -265);
DISPLAY 0.617021 (3360 -265);
PAINT ORANGE (3360 -265);
FORCEPROP 1 LASTPIN (3350 -50) $PN 1
J 0
(3360 -65);
DISPLAY 0.617021 (3360 -65);
PAINT ORANGE (3360 -65);
FORCEPROP 1 LAST MATERIAL ALUM
J 0
(3400 -250);
DISPLAY 0.617021 (3400 -250);
PAINT SKYBLUE (3400 -250);
FORCEPROP 1 LAST VOLTAGE 2.5V
J 0
(3400 -200);
DISPLAY 0.617021 (3400 -200);
PAINT SKYBLUE (3400 -200);
FORCEPROP 1 LAST TOLERANCE 20%
J 0
(3400 -150);
DISPLAY 0.617021 (3400 -150);
PAINT SKYBLUE (3400 -150);
FORCEPROP 1 LAST VALUE 470UF
J 0
(3400 -100);
DISPLAY 0.617021 (3400 -100);
PAINT SKYBLUE (3400 -100);
FORCEPROP 1 LAST LOCATION C3L14
J 0
(3400 -50);
DISPLAY 0.617021 (3400 -50);
PAINT AQUA (3400 -50);
FORCEPROP 1 LAST PART_NUMBER 699013-049
J 0
(3400 -350);
DISPLAY 0.617021 (3400 -350);
PAINT BLUE (3400 -350);
FORCEPROP 2 LAST CDS_LIB mstr_discrete
J 0
(3350 -150);
PAINT ORANGE (3350 -150);
DISPLAY INVISIBLE (3350 -150);
FORCEPROP 2 LAST CDS_LOCATION C3L14
J 0
(3400 -50);
DISPLAY 0.617021 (3400 -50);
PAINT AQUA (3400 -50);
DISPLAY INVISIBLE (3400 -50);
FORCEPROP 1 LAST PATH I76
J 0
(3400 0);
DISPLAY 1.319149 (3400 0);
PAINT ORANGE (3400 0);
DISPLAY INVISIBLE (3400 0);
FORCEPROP 0 LAST ROOM VDDQ_DEF_PWR_VR
J 0
(3400 0);
DISPLAY 1.021277 (3400 0);
PAINT ORANGE (3400 0);
DISPLAY INVISIBLE (3400 0);
FORCEPROP 2 LAST SEC_TYPE 3018
J 0
(3400 75);
DISPLAY 1.021277 (3400 75);
PAINT ORANGE (3400 75);
DISPLAY INVISIBLE (3400 75);
FORCEPROP 2 LAST SEC 1
J 0
(3400 75);
DISPLAY 0.680851 (3400 75);
PAINT MONO (3400 75);
DISPLAY INVISIBLE (3400 75);
FORCEADD CAPP..1
(3775 -150);
FORCEPROP 1 LASTPIN (3775 -250) $PN 2
J 0
(3785 -265);
DISPLAY 0.617021 (3785 -265);
PAINT ORANGE (3785 -265);
FORCEPROP 1 LASTPIN (3775 -50) $PN 1
J 0
(3785 -65);
DISPLAY 0.617021 (3785 -65);
PAINT ORANGE (3785 -65);
FORCEPROP 1 LAST MATERIAL ALUM
J 0
(3825 -250);
DISPLAY 0.617021 (3825 -250);
PAINT SKYBLUE (3825 -250);
FORCEPROP 1 LAST VOLTAGE 2.5V
J 0
(3825 -200);
DISPLAY 0.617021 (3825 -200);
PAINT SKYBLUE (3825 -200);
FORCEPROP 1 LAST PACK_TYPE 3018
J 0
(3825 -300);
DISPLAY 0.617021 (3825 -300);
PAINT SKYBLUE (3825 -300);
FORCEPROP 1 LAST TOLERANCE 20%
J 0
(3825 -150);
DISPLAY 0.617021 (3825 -150);
PAINT SKYBLUE (3825 -150);
FORCEPROP 1 LAST VALUE 470UF
J 0
(3825 -100);
DISPLAY 0.617021 (3825 -100);
PAINT SKYBLUE (3825 -100);
FORCEPROP 1 LAST LOCATION C6A5
J 0
(3825 -50);
DISPLAY 0.617021 (3825 -50);
PAINT AQUA (3825 -50);
FORCEPROP 1 LAST PART_NUMBER 699013-049
J 0
(3825 -350);
DISPLAY 0.617021 (3825 -350);
PAINT BLUE (3825 -350);
FORCEPROP 2 LAST CDS_LIB mstr_discrete
J 0
(3775 -150);
PAINT ORANGE (3775 -150);
DISPLAY INVISIBLE (3775 -150);
FORCEPROP 2 LAST CDS_LOCATION C6A5
J 0
(3825 -50);
DISPLAY 0.617021 (3825 -50);
PAINT AQUA (3825 -50);
DISPLAY INVISIBLE (3825 -50);
FORCEPROP 1 LAST PATH I77
J 0
(3825 0);
DISPLAY 1.319149 (3825 0);
PAINT ORANGE (3825 0);
DISPLAY INVISIBLE (3825 0);
FORCEPROP 0 LAST ROOM VDDQ_DEF_PWR_VR
J 0
(3825 0);
DISPLAY 1.021277 (3825 0);
PAINT ORANGE (3825 0);
DISPLAY INVISIBLE (3825 0);
FORCEPROP 2 LAST SEC_TYPE 3018
J 0
(3825 75);
DISPLAY 1.021277 (3825 75);
PAINT ORANGE (3825 75);
DISPLAY INVISIBLE (3825 75);
FORCEPROP 2 LAST SEC 1
J 0
(3825 75);
DISPLAY 0.680851 (3825 75);
PAINT MONO (3825 75);
DISPLAY INVISIBLE (3825 75);
FORCEADD CAPP..1
(4175 -175);
FORCEPROP 1 LASTPIN (4175 -275) $PN 2
J 0
(4185 -290);
DISPLAY 0.617021 (4185 -290);
PAINT ORANGE (4185 -290);
FORCEPROP 1 LAST PACK_TYPE 3018
J 0
(4225 -325);
DISPLAY 0.617021 (4225 -325);
PAINT SKYBLUE (4225 -325);
FORCEPROP 1 LAST MATERIAL ALUM
J 0
(4225 -275);
DISPLAY 0.617021 (4225 -275);
PAINT SKYBLUE (4225 -275);
FORCEPROP 1 LASTPIN (4175 -75) $PN 1
J 0
(4185 -90);
DISPLAY 0.617021 (4185 -90);
PAINT ORANGE (4185 -90);
FORCEPROP 1 LAST VOLTAGE 2.5V
J 0
(4225 -225);
DISPLAY 0.617021 (4225 -225);
PAINT SKYBLUE (4225 -225);
FORCEPROP 1 LAST TOLERANCE 20%
J 0
(4225 -175);
DISPLAY 0.617021 (4225 -175);
PAINT SKYBLUE (4225 -175);
FORCEPROP 1 LAST LOCATION C4L5
J 0
(4225 -75);
DISPLAY 0.617021 (4225 -75);
PAINT AQUA (4225 -75);
FORCEPROP 1 LAST VALUE 470UF
J 0
(4225 -125);
DISPLAY 0.617021 (4225 -125);
PAINT SKYBLUE (4225 -125);
FORCEPROP 1 LAST PART_NUMBER 699013-049
J 0
(4225 -375);
DISPLAY 0.617021 (4225 -375);
PAINT BLUE (4225 -375);
FORCEPROP 2 LAST CDS_LIB mstr_discrete
J 0
(4175 -175);
PAINT ORANGE (4175 -175);
DISPLAY INVISIBLE (4175 -175);
FORCEPROP 2 LAST CDS_LOCATION C4L5
J 0
(4225 -75);
DISPLAY 0.617021 (4225 -75);
PAINT AQUA (4225 -75);
DISPLAY INVISIBLE (4225 -75);
FORCEPROP 1 LAST PATH I78
J 0
(4225 -25);
DISPLAY 1.319149 (4225 -25);
PAINT ORANGE (4225 -25);
DISPLAY INVISIBLE (4225 -25);
FORCEPROP 0 LAST ROOM VDDQ_DEF_PWR_VR
J 0
(4225 -25);
DISPLAY 1.021277 (4225 -25);
PAINT ORANGE (4225 -25);
DISPLAY INVISIBLE (4225 -25);
FORCEPROP 2 LAST SEC 1
J 0
(4225 50);
DISPLAY 0.680851 (4225 50);
PAINT MONO (4225 50);
DISPLAY INVISIBLE (4225 50);
FORCEPROP 2 LAST SEC_TYPE 3018
J 0
(4225 50);
DISPLAY 1.021277 (4225 50);
PAINT ORANGE (4225 50);
DISPLAY INVISIBLE (4225 50);
FORCEADD PVDDQ_DEF..1
(2925 150);
FORCEPROP 3 LASTPIN (2925 100) SIG_NAME PVDDQ_DEF\g
J 0
(2935 110);
DISPLAY 0.659574 (2935 110);
PAINT MONO (2935 110);
DISPLAY INVISIBLE (2935 110);
FORCEPROP 1 LAST BODY_TYPE PLUMBING
J 0
(2880 107);
DISPLAY 0.340426 (2880 107);
PAINT GREEN (2880 107);
DISPLAY INVISIBLE (2880 107);
FORCEPROP 1 LAST VOLTAGE 1.2V
J 0
(2880 107);
DISPLAY 0.340426 (2880 107);
PAINT SKYBLUE (2880 107);
DISPLAY INVISIBLE (2880 107);
FORCEPROP 2 LAST CDS_LIB mstr_symbols
J 0
(2925 150);
PAINT ORANGE (2925 150);
DISPLAY INVISIBLE (2925 150);
FORCEPROP 1 LAST HDL_POWER PVDDQ_DEF
J 1
(2925 200);
DISPLAY 0.872340 (2925 200);
PAINT GREEN (2925 200);
DISPLAY INVISIBLE (2925 200);
FORCEPROP 1 LAST PATH I80
J 0
(2975 175);
DISPLAY 0.872340 (2975 175);
PAINT AQUA (2975 175);
DISPLAY INVISIBLE (2975 175);
FORCEPROP 2 LAST BOM_COST MEM_VRD_PVPP_DEF
J 0
(2975 250);
PAINT MONO (2975 250);
DISPLAY INVISIBLE (2975 250);
FORCEPROP 2 LAST ROOM VDDQ_DEF_PWR_VR
J 0
(3150 250);
PAINT ORANGE (3150 250);
DISPLAY INVISIBLE (3150 250);
FORCEADD GND..1
(2925 -575);
FORCEPROP 3 LASTPIN (2925 -525) SIG_NAME GND\g
J 0
(2935 -515);
DISPLAY 0.659574 (2935 -515);
PAINT MONO (2935 -515);
DISPLAY INVISIBLE (2935 -515);
FORCEPROP 1 LAST PATH I81
J 0
(3000 -575);
DISPLAY 1.170213 (3000 -575);
PAINT AQUA (3000 -575);
DISPLAY INVISIBLE (3000 -575);
FORCEPROP 1 LAST BODY_TYPE PLUMBING
J 0
(2880 -618);
DISPLAY 0.340426 (2880 -618);
PAINT GREEN (2880 -618);
DISPLAY INVISIBLE (2880 -618);
FORCEPROP 2 LAST CDS_LIB mstr_symbols
J 0
(2925 -575);
PAINT ORANGE (2925 -575);
DISPLAY INVISIBLE (2925 -575);
FORCEPROP 1 LAST SIZE 1B
J 0
(3000 -625);
DISPLAY 0.893617 (3000 -625);
PAINT GREEN (3000 -625);
DISPLAY INVISIBLE (3000 -625);
FORCEPROP 1 LAST VOLTAGE 0
J 0
(2925 -575);
PAINT SKYBLUE (2925 -575);
DISPLAY INVISIBLE (2925 -575);
FORCEPROP 1 LAST HDL_POWER GND
J 0
(2925 -425);
DISPLAY 0.893617 (2925 -425);
PAINT GREEN (2925 -425);
DISPLAY INVISIBLE (2925 -425);
FORCEADD CAP..1
(5000 2825);
FORCEPROP 1 LASTPIN (5000 2725) $PN 2
J 0
(5010 2705);
DISPLAY 0.617021 (5010 2705);
PAINT ORANGE (5010 2705);
FORCEPROP 1 LAST VOLTAGE 4V
J 0
(5050 2825);
DISPLAY 0.617021 (5050 2825);
PAINT SKYBLUE (5050 2825);
FORCEPROP 1 LASTPIN (5000 2925) $PN 1
J 0
(5010 2905);
DISPLAY 0.617021 (5010 2905);
PAINT ORANGE (5010 2905);
FORCEPROP 1 LAST MATERIAL X5R
J 0
(5050 2725);
DISPLAY 0.617021 (5050 2725);
PAINT SKYBLUE (5050 2725);
FORCEPROP 1 LAST PACK_TYPE 0805
J 0
(5050 2625);
DISPLAY 0.617021 (5050 2625);
PAINT SKYBLUE (5050 2625);
FORCEPROP 1 LAST TOLERANCE 20%
J 0
(5050 2775);
DISPLAY 0.617021 (5050 2775);
PAINT SKYBLUE (5050 2775);
FORCEPROP 1 LAST VALUE 100UF
J 0
(5050 2875);
DISPLAY 0.617021 (5050 2875);
PAINT SKYBLUE (5050 2875);
FORCEPROP 1 LAST PART_NUMBER 602433-112
J 0
(5050 2675);
DISPLAY 0.617021 (5050 2675);
PAINT BLUE (5050 2675);
FORCEPROP 1 LAST LOCATION C5M8
J 0
(5050 2925);
DISPLAY 0.617021 (5050 2925);
PAINT AQUA (5050 2925);
FORCEPROP 2 LAST CDS_LIB mstr_discrete
J 0
(5000 2825);
PAINT MONO (5000 2825);
DISPLAY INVISIBLE (5000 2825);
FORCEPROP 2 LAST CDS_LOCATION C5M8
J 0
(5050 2925);
DISPLAY 0.617021 (5050 2925);
PAINT AQUA (5050 2925);
DISPLAY INVISIBLE (5050 2925);
FORCEPROP 2 LAST SEC_TYPE 0805
J 0
(5050 3025);
DISPLAY 1.021277 (5050 3025);
PAINT ORANGE (5050 3025);
DISPLAY INVISIBLE (5050 3025);
FORCEPROP 2 LAST BOM_COST MEM_VRD_PVDDQ_DEF
J 0
(5050 2975);
PAINT MONO (5050 2975);
DISPLAY INVISIBLE (5050 2975);
FORCEPROP 2 LAST SEC 1
J 0
(5050 3025);
DISPLAY 0.680851 (5050 3025);
PAINT MONO (5050 3025);
DISPLAY INVISIBLE (5050 3025);
FORCEPROP 1 LAST PATH I82
J 0
(5050 2975);
DISPLAY 0.978723 (5050 2975);
PAINT WHITE (5050 2975);
DISPLAY INVISIBLE (5050 2975);
FORCEPROP 2 LAST ROOM VDDQ_DEF_PWR_VR
J 0
(5050 2975);
PAINT MONO (5050 2975);
DISPLAY INVISIBLE (5050 2975);
FORCEADD CAP..1
(4600 2825);
FORCEPROP 1 LASTPIN (4600 2925) $PN 1
J 0
(4610 2905);
DISPLAY 0.617021 (4610 2905);
PAINT ORANGE (4610 2905);
FORCEPROP 1 LASTPIN (4600 2725) $PN 2
J 0
(4610 2705);
DISPLAY 0.617021 (4610 2705);
PAINT ORANGE (4610 2705);
FORCEPROP 1 LAST MATERIAL X5R
J 0
(4650 2725);
DISPLAY 0.617021 (4650 2725);
PAINT SKYBLUE (4650 2725);
FORCEPROP 1 LAST VOLTAGE 4V
J 0
(4650 2825);
DISPLAY 0.617021 (4650 2825);
PAINT SKYBLUE (4650 2825);
FORCEPROP 1 LAST PACK_TYPE 0805
J 0
(4650 2625);
DISPLAY 0.617021 (4650 2625);
PAINT SKYBLUE (4650 2625);
FORCEPROP 1 LAST TOLERANCE 20%
J 0
(4650 2775);
DISPLAY 0.617021 (4650 2775);
PAINT SKYBLUE (4650 2775);
FORCEPROP 1 LAST VALUE 100UF
J 0
(4650 2875);
DISPLAY 0.617021 (4650 2875);
PAINT SKYBLUE (4650 2875);
FORCEPROP 1 LAST LOCATION C5L14
J 0
(4650 2925);
DISPLAY 0.617021 (4650 2925);
PAINT AQUA (4650 2925);
FORCEPROP 1 LAST PART_NUMBER 602433-112
J 0
(4650 2675);
DISPLAY 0.617021 (4650 2675);
PAINT BLUE (4650 2675);
FORCEPROP 2 LAST CDS_LIB mstr_discrete
J 0
(4600 2825);
PAINT MONO (4600 2825);
DISPLAY INVISIBLE (4600 2825);
FORCEPROP 1 LAST PATH I83
J 0
(4650 2975);
DISPLAY 0.978723 (4650 2975);
PAINT WHITE (4650 2975);
DISPLAY INVISIBLE (4650 2975);
FORCEPROP 2 LAST CDS_LOCATION C5L14
J 0
(4650 2925);
DISPLAY 0.617021 (4650 2925);
PAINT AQUA (4650 2925);
DISPLAY INVISIBLE (4650 2925);
FORCEPROP 2 LAST SEC 1
J 0
(4650 3025);
DISPLAY 0.680851 (4650 3025);
PAINT MONO (4650 3025);
DISPLAY INVISIBLE (4650 3025);
FORCEPROP 2 LAST BOM_COST MEM_VRD_PVDDQ_DEF
J 0
(4650 2975);
PAINT MONO (4650 2975);
DISPLAY INVISIBLE (4650 2975);
FORCEPROP 2 LAST SEC_TYPE 0805
J 0
(4650 3025);
DISPLAY 1.021277 (4650 3025);
PAINT ORANGE (4650 3025);
DISPLAY INVISIBLE (4650 3025);
FORCEPROP 2 LAST ROOM VDDQ_DEF_PWR_VR
J 0
(4650 2975);
PAINT MONO (4650 2975);
DISPLAY INVISIBLE (4650 2975);
FORCEADD CAP..1
(4250 2825);
FORCEPROP 1 LASTPIN (4250 2725) $PN 2
J 0
(4260 2705);
DISPLAY 0.617021 (4260 2705);
PAINT ORANGE (4260 2705);
FORCEPROP 1 LASTPIN (4250 2925) $PN 1
J 0
(4260 2905);
DISPLAY 0.617021 (4260 2905);
PAINT ORANGE (4260 2905);
FORCEPROP 1 LAST MATERIAL X5R
J 0
(4300 2725);
DISPLAY 0.617021 (4300 2725);
PAINT SKYBLUE (4300 2725);
FORCEPROP 1 LAST VOLTAGE 4V
J 0
(4300 2825);
DISPLAY 0.617021 (4300 2825);
PAINT SKYBLUE (4300 2825);
FORCEPROP 1 LAST PACK_TYPE 0805
J 0
(4300 2625);
DISPLAY 0.617021 (4300 2625);
PAINT SKYBLUE (4300 2625);
FORCEPROP 1 LAST TOLERANCE 20%
J 0
(4300 2775);
DISPLAY 0.617021 (4300 2775);
PAINT SKYBLUE (4300 2775);
FORCEPROP 1 LAST VALUE 100UF
J 0
(4300 2875);
DISPLAY 0.617021 (4300 2875);
PAINT SKYBLUE (4300 2875);
FORCEPROP 1 LAST PART_NUMBER 602433-112
J 0
(4300 2675);
DISPLAY 0.617021 (4300 2675);
PAINT BLUE (4300 2675);
FORCEPROP 1 LAST LOCATION C5M12
J 0
(4300 2925);
DISPLAY 0.617021 (4300 2925);
PAINT AQUA (4300 2925);
FORCEPROP 2 LAST CDS_LIB mstr_discrete
J 0
(4250 2825);
PAINT MONO (4250 2825);
DISPLAY INVISIBLE (4250 2825);
FORCEPROP 2 LAST CDS_LOCATION C5M12
J 0
(4300 2925);
DISPLAY 0.617021 (4300 2925);
PAINT AQUA (4300 2925);
DISPLAY INVISIBLE (4300 2925);
FORCEPROP 2 LAST BOM_COST MEM_VRD_PVDDQ_DEF
J 0
(4300 2975);
PAINT MONO (4300 2975);
DISPLAY INVISIBLE (4300 2975);
FORCEPROP 2 LAST SEC 1
J 0
(4300 3025);
DISPLAY 0.680851 (4300 3025);
PAINT MONO (4300 3025);
DISPLAY INVISIBLE (4300 3025);
FORCEPROP 2 LAST SEC_TYPE 0805
J 0
(4300 3025);
DISPLAY 1.021277 (4300 3025);
PAINT ORANGE (4300 3025);
DISPLAY INVISIBLE (4300 3025);
FORCEPROP 1 LAST PATH I88
J 0
(4300 2975);
DISPLAY 0.978723 (4300 2975);
PAINT WHITE (4300 2975);
DISPLAY INVISIBLE (4300 2975);
FORCEPROP 2 LAST ROOM VDDQ_DEF_PWR_VR
J 0
(4300 2975);
PAINT MONO (4300 2975);
DISPLAY INVISIBLE (4300 2975);
FORCEADD CAP..1
(3850 2825);
FORCEPROP 1 LAST TOLERANCE 20%
J 0
(3900 2775);
DISPLAY 0.617021 (3900 2775);
PAINT SKYBLUE (3900 2775);
FORCEPROP 1 LAST PACK_TYPE 0805
J 0
(3900 2625);
DISPLAY 0.617021 (3900 2625);
PAINT SKYBLUE (3900 2625);
FORCEPROP 1 LAST MATERIAL X5R
J 0
(3900 2725);
DISPLAY 0.617021 (3900 2725);
PAINT SKYBLUE (3900 2725);
FORCEPROP 1 LASTPIN (3850 2725) $PN 2
J 0
(3860 2705);
DISPLAY 0.617021 (3860 2705);
PAINT ORANGE (3860 2705);
FORCEPROP 1 LAST VOLTAGE 4V
J 0
(3900 2825);
DISPLAY 0.617021 (3900 2825);
PAINT SKYBLUE (3900 2825);
FORCEPROP 1 LASTPIN (3850 2925) $PN 1
J 0
(3860 2905);
DISPLAY 0.617021 (3860 2905);
PAINT ORANGE (3860 2905);
FORCEPROP 1 LAST LOCATION C5L3
J 0
(3900 2925);
DISPLAY 0.617021 (3900 2925);
PAINT AQUA (3900 2925);
FORCEPROP 1 LAST VALUE 100UF
J 0
(3900 2875);
DISPLAY 0.617021 (3900 2875);
PAINT SKYBLUE (3900 2875);
FORCEPROP 1 LAST PART_NUMBER 602433-112
J 0
(3900 2675);
DISPLAY 0.617021 (3900 2675);
PAINT BLUE (3900 2675);
FORCEPROP 2 LAST CDS_LIB mstr_discrete
J 0
(3850 2825);
PAINT MONO (3850 2825);
DISPLAY INVISIBLE (3850 2825);
FORCEPROP 2 LAST CDS_LOCATION C5L3
J 0
(3900 2925);
DISPLAY 0.617021 (3900 2925);
PAINT AQUA (3900 2925);
DISPLAY INVISIBLE (3900 2925);
FORCEPROP 2 LAST SEC 1
J 0
(3900 3025);
DISPLAY 0.680851 (3900 3025);
PAINT MONO (3900 3025);
DISPLAY INVISIBLE (3900 3025);
FORCEPROP 1 LAST PATH I89
J 0
(3900 2975);
DISPLAY 0.978723 (3900 2975);
PAINT WHITE (3900 2975);
DISPLAY INVISIBLE (3900 2975);
FORCEPROP 2 LAST SEC_TYPE 0805
J 0
(3900 3025);
DISPLAY 1.021277 (3900 3025);
PAINT ORANGE (3900 3025);
DISPLAY INVISIBLE (3900 3025);
FORCEPROP 2 LAST BOM_COST MEM_VRD_PVDDQ_DEF
J 0
(3900 2975);
PAINT MONO (3900 2975);
DISPLAY INVISIBLE (3900 2975);
FORCEPROP 2 LAST ROOM VDDQ_DEF_PWR_VR
J 0
(3900 2975);
PAINT MONO (3900 2975);
DISPLAY INVISIBLE (3900 2975);
FORCEADD CAP..1
(3500 2825);
FORCEPROP 1 LASTPIN (3500 2725) $PN 2
J 0
(3510 2705);
DISPLAY 0.617021 (3510 2705);
PAINT ORANGE (3510 2705);
FORCEPROP 1 LASTPIN (3500 2925) $PN 1
J 0
(3510 2905);
DISPLAY 0.617021 (3510 2905);
PAINT ORANGE (3510 2905);
FORCEPROP 1 LAST MATERIAL X5R
J 0
(3550 2725);
DISPLAY 0.617021 (3550 2725);
PAINT SKYBLUE (3550 2725);
FORCEPROP 1 LAST VOLTAGE 4V
J 0
(3550 2825);
DISPLAY 0.617021 (3550 2825);
PAINT SKYBLUE (3550 2825);
FORCEPROP 1 LAST PACK_TYPE 0805
J 0
(3550 2625);
DISPLAY 0.617021 (3550 2625);
PAINT SKYBLUE (3550 2625);
FORCEPROP 1 LAST TOLERANCE 20%
J 0
(3550 2775);
DISPLAY 0.617021 (3550 2775);
PAINT SKYBLUE (3550 2775);
FORCEPROP 1 LAST VALUE 100UF
J 0
(3550 2875);
DISPLAY 0.617021 (3550 2875);
PAINT SKYBLUE (3550 2875);
FORCEPROP 1 LAST PART_NUMBER 602433-112
J 0
(3550 2675);
DISPLAY 0.617021 (3550 2675);
PAINT BLUE (3550 2675);
FORCEPROP 1 LAST LOCATION C5L2
J 0
(3550 2925);
DISPLAY 0.617021 (3550 2925);
PAINT AQUA (3550 2925);
FORCEPROP 2 LAST CDS_LIB mstr_discrete
J 0
(3500 2825);
PAINT MONO (3500 2825);
DISPLAY INVISIBLE (3500 2825);
FORCEPROP 2 LAST CDS_LOCATION C5L2
J 0
(3550 2925);
DISPLAY 0.617021 (3550 2925);
PAINT AQUA (3550 2925);
DISPLAY INVISIBLE (3550 2925);
FORCEPROP 2 LAST BOM_COST MEM_VRD_PVDDQ_DEF
J 0
(3550 2975);
PAINT MONO (3550 2975);
DISPLAY INVISIBLE (3550 2975);
FORCEPROP 2 LAST SEC_TYPE 0805
J 0
(3550 3025);
DISPLAY 1.021277 (3550 3025);
PAINT ORANGE (3550 3025);
DISPLAY INVISIBLE (3550 3025);
FORCEPROP 2 LAST SEC 1
J 0
(3550 3025);
DISPLAY 0.680851 (3550 3025);
PAINT MONO (3550 3025);
DISPLAY INVISIBLE (3550 3025);
FORCEPROP 1 LAST PATH I90
J 0
(3550 2975);
DISPLAY 0.978723 (3550 2975);
PAINT WHITE (3550 2975);
DISPLAY INVISIBLE (3550 2975);
FORCEPROP 2 LAST ROOM VDDQ_DEF_PWR_VR
J 0
(3550 2975);
PAINT MONO (3550 2975);
DISPLAY INVISIBLE (3550 2975);
FORCEADD CAP..1
(3150 2825);
FORCEPROP 1 LAST TOLERANCE 20%
J 0
(3200 2775);
DISPLAY 0.617021 (3200 2775);
PAINT SKYBLUE (3200 2775);
FORCEPROP 1 LAST PACK_TYPE 0805
J 0
(3200 2625);
DISPLAY 0.617021 (3200 2625);
PAINT SKYBLUE (3200 2625);
FORCEPROP 1 LAST MATERIAL X5R
J 0
(3200 2725);
DISPLAY 0.617021 (3200 2725);
PAINT SKYBLUE (3200 2725);
FORCEPROP 1 LASTPIN (3150 2725) $PN 2
J 0
(3160 2705);
DISPLAY 0.617021 (3160 2705);
PAINT ORANGE (3160 2705);
FORCEPROP 1 LASTPIN (3150 2925) $PN 1
J 0
(3160 2905);
DISPLAY 0.617021 (3160 2905);
PAINT ORANGE (3160 2905);
FORCEPROP 1 LAST VOLTAGE 4V
J 0
(3200 2825);
DISPLAY 0.617021 (3200 2825);
PAINT SKYBLUE (3200 2825);
FORCEPROP 1 LAST LOCATION C5L1
J 0
(3200 2925);
DISPLAY 0.617021 (3200 2925);
PAINT AQUA (3200 2925);
FORCEPROP 1 LAST VALUE 100UF
J 0
(3200 2875);
DISPLAY 0.617021 (3200 2875);
PAINT SKYBLUE (3200 2875);
FORCEPROP 1 LAST PART_NUMBER 602433-112
J 0
(3200 2675);
DISPLAY 0.617021 (3200 2675);
PAINT BLUE (3200 2675);
FORCEPROP 2 LAST CDS_LIB mstr_discrete
J 0
(3150 2825);
PAINT MONO (3150 2825);
DISPLAY INVISIBLE (3150 2825);
FORCEPROP 2 LAST ROOM VDDQ_DEF_PWR_VR
J 0
(3200 2975);
PAINT MONO (3200 2975);
DISPLAY INVISIBLE (3200 2975);
FORCEPROP 2 LAST BOM_COST MEM_VRD_PVDDQ_DEF
J 0
(3200 2975);
PAINT MONO (3200 2975);
DISPLAY INVISIBLE (3200 2975);
FORCEPROP 2 LAST SEC_TYPE 0805
J 0
(3200 3025);
DISPLAY 1.021277 (3200 3025);
PAINT ORANGE (3200 3025);
DISPLAY INVISIBLE (3200 3025);
FORCEPROP 2 LAST SEC 1
J 0
(3200 3025);
DISPLAY 0.680851 (3200 3025);
PAINT MONO (3200 3025);
DISPLAY INVISIBLE (3200 3025);
FORCEPROP 2 LAST CDS_LOCATION C5L1
J 0
(3200 2925);
DISPLAY 0.617021 (3200 2925);
PAINT AQUA (3200 2925);
DISPLAY INVISIBLE (3200 2925);
FORCEPROP 1 LAST PATH I91
J 0
(3200 2975);
DISPLAY 0.978723 (3200 2975);
PAINT WHITE (3200 2975);
DISPLAY INVISIBLE (3200 2975);
FORCEADD CAP..1
(2750 2825);
FORCEPROP 1 LASTPIN (2750 2725) $PN 2
J 0
(2760 2705);
DISPLAY 0.617021 (2760 2705);
PAINT ORANGE (2760 2705);
FORCEPROP 1 LASTPIN (2750 2925) $PN 1
J 0
(2760 2905);
DISPLAY 0.617021 (2760 2905);
PAINT ORANGE (2760 2905);
FORCEPROP 1 LAST MATERIAL X5R
J 0
(2800 2725);
DISPLAY 0.617021 (2800 2725);
PAINT SKYBLUE (2800 2725);
FORCEPROP 1 LAST VOLTAGE 4V
J 0
(2800 2825);
DISPLAY 0.617021 (2800 2825);
PAINT SKYBLUE (2800 2825);
FORCEPROP 1 LAST PACK_TYPE 0805
J 0
(2800 2625);
DISPLAY 0.617021 (2800 2625);
PAINT SKYBLUE (2800 2625);
FORCEPROP 1 LAST TOLERANCE 20%
J 0
(2800 2775);
DISPLAY 0.617021 (2800 2775);
PAINT SKYBLUE (2800 2775);
FORCEPROP 1 LAST VALUE 100UF
J 0
(2800 2875);
DISPLAY 0.617021 (2800 2875);
PAINT SKYBLUE (2800 2875);
FORCEPROP 1 LAST LOCATION C5A20
J 0
(2800 2925);
DISPLAY 0.617021 (2800 2925);
PAINT AQUA (2800 2925);
FORCEPROP 1 LAST PART_NUMBER 602433-112
J 0
(2800 2675);
DISPLAY 0.617021 (2800 2675);
PAINT BLUE (2800 2675);
FORCEPROP 2 LAST CDS_LIB mstr_discrete
J 0
(2750 2825);
PAINT MONO (2750 2825);
DISPLAY INVISIBLE (2750 2825);
FORCEPROP 2 LAST CDS_LOCATION C5A20
J 0
(2800 2925);
DISPLAY 0.617021 (2800 2925);
PAINT AQUA (2800 2925);
DISPLAY INVISIBLE (2800 2925);
FORCEPROP 2 LAST BOM_COST MEM_VRD_PVDDQ_DEF
J 0
(2800 2975);
PAINT MONO (2800 2975);
DISPLAY INVISIBLE (2800 2975);
FORCEPROP 2 LAST SEC_TYPE 0805
J 0
(2800 3025);
DISPLAY 1.021277 (2800 3025);
PAINT ORANGE (2800 3025);
DISPLAY INVISIBLE (2800 3025);
FORCEPROP 2 LAST SEC 1
J 0
(2800 3025);
DISPLAY 0.680851 (2800 3025);
PAINT MONO (2800 3025);
DISPLAY INVISIBLE (2800 3025);
FORCEPROP 1 LAST PATH I92
J 0
(2800 2975);
DISPLAY 0.978723 (2800 2975);
PAINT WHITE (2800 2975);
DISPLAY INVISIBLE (2800 2975);
FORCEPROP 2 LAST ROOM VDDQ_DEF_PWR_VR
J 0
(2800 2975);
PAINT MONO (2800 2975);
DISPLAY INVISIBLE (2800 2975);
FORCEADD PVDDQ_DEF..1
(2400 3100);
FORCEPROP 3 LASTPIN (2400 3050) SIG_NAME PVDDQ_DEF\g
J 0
(2410 3060);
DISPLAY 0.659574 (2410 3060);
PAINT MONO (2410 3060);
DISPLAY INVISIBLE (2410 3060);
FORCEPROP 1 LAST VOLTAGE 1.2V
J 0
(2355 3057);
DISPLAY 0.340426 (2355 3057);
PAINT SKYBLUE (2355 3057);
DISPLAY INVISIBLE (2355 3057);
FORCEPROP 1 LAST BODY_TYPE PLUMBING
J 0
(2355 3057);
DISPLAY 0.340426 (2355 3057);
PAINT GREEN (2355 3057);
DISPLAY INVISIBLE (2355 3057);
FORCEPROP 1 LAST PATH I93
J 0
(2450 3125);
DISPLAY 0.872340 (2450 3125);
PAINT AQUA (2450 3125);
DISPLAY INVISIBLE (2450 3125);
FORCEPROP 2 LAST CDS_LIB mstr_symbols
J 0
(2400 3100);
PAINT ORANGE (2400 3100);
DISPLAY INVISIBLE (2400 3100);
FORCEPROP 2 LAST BOM_COST MEM_VRD_PVDDQ_DEF
J 0
(2475 3200);
PAINT MONO (2475 3200);
DISPLAY INVISIBLE (2475 3200);
FORCEPROP 2 LAST ROOM VDDQ_DEF_PWR_VR
J 0
(2650 3200);
PAINT ORANGE (2650 3200);
DISPLAY INVISIBLE (2650 3200);
FORCEPROP 1 LAST HDL_POWER PVDDQ_DEF
J 1
(2400 3150);
DISPLAY 0.872340 (2400 3150);
PAINT GREEN (2400 3150);
DISPLAY INVISIBLE (2400 3150);
FORCEADD GND..1
(4125 2450);
FORCEPROP 3 LASTPIN (4125 2500) SIG_NAME GND\g
J 0
(4135 2510);
DISPLAY 0.659574 (4135 2510);
PAINT MONO (4135 2510);
DISPLAY INVISIBLE (4135 2510);
FORCEPROP 2 LAST ROOM VDDQ_DEF_PWR_VR
J 0
(3575 2525);
PAINT ORANGE (3575 2525);
DISPLAY INVISIBLE (3575 2525);
FORCEPROP 1 LAST BODY_TYPE PLUMBING
J 0
(4080 2407);
DISPLAY 0.340426 (4080 2407);
PAINT GREEN (4080 2407);
DISPLAY INVISIBLE (4080 2407);
FORCEPROP 2 LAST BOM_COST MEM_VRD_PVDDQ_DEF
J 0
(3800 2525);
PAINT MONO (3800 2525);
DISPLAY INVISIBLE (3800 2525);
FORCEPROP 1 LAST PATH I94
J 0
(4200 2450);
DISPLAY 1.170213 (4200 2450);
PAINT AQUA (4200 2450);
DISPLAY INVISIBLE (4200 2450);
FORCEPROP 2 LAST CDS_LIB mstr_symbols
J 0
(4125 2450);
PAINT ORANGE (4125 2450);
DISPLAY INVISIBLE (4125 2450);
FORCEPROP 1 LAST SIZE 1B
J 0
(4200 2400);
DISPLAY 0.893617 (4200 2400);
PAINT GREEN (4200 2400);
DISPLAY INVISIBLE (4200 2400);
FORCEPROP 1 LAST VOLTAGE 0
J 0
(4125 2450);
PAINT SKYBLUE (4125 2450);
DISPLAY INVISIBLE (4125 2450);
FORCEPROP 1 LAST HDL_POWER GND
J 0
(4125 2600);
DISPLAY 0.893617 (4125 2600);
PAINT GREEN (4125 2600);
DISPLAY INVISIBLE (4125 2600);
FORCEADD DNS..2
(-695 1820);
PAINT RED (-695 1820);
FORCEPROP 1 LAST COMMENT_BODY TRUE
R 1
J 0
(-620 1595);
DISPLAY 0.872340 (-620 1595);
PAINT GREEN (-620 1595);
DISPLAY INVISIBLE (-620 1595);
FORCEPROP 2 LAST CDS_LIB mstr_misc
J 0
(-695 1820);
PAINT ORANGE (-695 1820);
DISPLAY INVISIBLE (-695 1820);
FORCEADD DNS..3
(-320 1620);
PAINT RED (-320 1620);
FORCEPROP 1 LAST COMMENT_BODY TRUE
R 1
J 0
(-245 1395);
DISPLAY 0.872340 (-245 1395);
PAINT GREEN (-245 1395);
DISPLAY INVISIBLE (-245 1395);
FORCEPROP 2 LAST CDS_LIB mstr_misc
J 0
(-320 1620);
PAINT ORANGE (-320 1620);
DISPLAY INVISIBLE (-320 1620);
FORCEADD DNS..3
(-295 2070);
PAINT RED (-295 2070);
FORCEPROP 1 LAST COMMENT_BODY TRUE
R 1
J 0
(-220 1845);
DISPLAY 0.872340 (-220 1845);
PAINT GREEN (-220 1845);
DISPLAY INVISIBLE (-220 1845);
FORCEPROP 2 LAST CDS_LIB mstr_misc
J 0
(-295 2070);
PAINT ORANGE (-295 2070);
DISPLAY INVISIBLE (-295 2070);
FORCEADD INTEL_CORP_BPAGE..1
(5475 -1550);
FORCEPROP 1 LAST CDS_CON_LAST_MODIFIED Tue Dec 01 11:52:26 2015
J 0
(4050 -1225);
PAINT GREEN (4050 -1225);
DISPLAY INVISIBLE (4050 -1225);
FORCEPROP 1 LAST CUSTOM_TXT_CDS <CURRENT_DESIGN_SHEET> OF <TOTAL_DESIGN_SHEETS>
J 0
(4975 -1525);
PAINT GREEN (4975 -1525);
FORCEPROP 2 LAST CUSTOM_TXT_CDS <XR_PAGE_TITLE>
J 0
(-2415 3700);
DISPLAY 0.638298 (-2415 3700);
PAINT PINK (-2415 3700);
DISPLAY INVISIBLE (-2415 3700);
FORCEPROP 2 LAST CUSTOM_TXT_CDS <CON_PAGE_NUM> OF <CON_TOTAL_PAGES>
J 0
(4975 -1525);
PAINT GREEN (4975 -1525);
FORCEPROP 2 LAST CUSTOM_TXT_CDS <CON_LAST_MODIFIED>
J 0
(4525 -1200);
PAINT GREEN (4525 -1200);
FORCEPROP 1 LAST SCH_TITLE VDDQ DEF DECAP (3 OF 3)
J 0
(-2475 -1500);
DISPLAY 1.212766 (-2475 -1500);
PAINT GREEN (-2475 -1500);
FORCEPROP 1 LAST SCH_ADDRESS2 P.O. BOX 58119
J 0
(1500 -1475);
DISPLAY 0.617021 (1500 -1475);
PAINT GREEN (1500 -1475);
FORCEPROP 1 LAST SCH_ADDRESS1 2200 Mission College Blvd.
J 0
(1500 -1425);
DISPLAY 0.617021 (1500 -1425);
PAINT GREEN (1500 -1425);
FORCEPROP 1 LAST SCH_ADDRESS3 Santa Clara, CA 95052-8119
J 0
(1500 -1525);
DISPLAY 0.617021 (1500 -1525);
PAINT GREEN (1500 -1525);
FORCEPROP 1 LAST SCH_REV 2.420
J 0
(5225 -1400);
DISPLAY 0.978723 (5225 -1400);
PAINT YELLOW (5225 -1400);
FORCEPROP 1 LAST SCH_DEPT BESD
J 1
(1025 -1450);
DISPLAY 1.212766 (1025 -1450);
PAINT YELLOW (1025 -1450);
FORCEPROP 1 LAST SCH_NUMBER H4694802
J 0
(4175 -1400);
DISPLAY 1.212766 (4175 -1400);
PAINT YELLOW (4175 -1400);
FORCEPROP 2 LAST ROOM VDDQ_DEF_PWR_VR
J 0
(-2625 3550);
PAINT ORANGE (-2625 3550);
DISPLAY INVISIBLE (-2625 3550);
FORCEPROP 2 LAST PAGE_BORDER TRUE
J 0
(-2415 3700);
DISPLAY 0.851064 (-2415 3700);
PAINT PINK (-2415 3700);
DISPLAY INVISIBLE (-2415 3700);
FORCEPROP 1 LAST COMMENT_BODY TRUE
J 0
(5487 -1538);
DISPLAY 0.446809 (5487 -1538);
PAINT GREEN (5487 -1538);
DISPLAY INVISIBLE (5487 -1538);
FORCEPROP 2 LAST CDS_LIB mstr_symbols
J 0
(5475 -1550);
PAINT ORANGE (5475 -1550);
DISPLAY INVISIBLE (5475 -1550);
FORCEPROP 2 LAST CDS_XR_PAGE_TITLE CR-220 : @BASEBOARD_FAB2_LIB.BASEBOARD_FAB2(SCH_1):PAGE220
J 0
(-2415 3700);
DISPLAY 0.638298 (-2415 3700);
PAINT PINK (-2415 3700);
DISPLAY INVISIBLE (-2415 3700);
WIRE 16 -1 (4525 1775)(4525 1850);
WIRE 16 -1 (4525 1850)(4125 1850);
WIRE 16 -1 (4125 1775)(4125 1850);
WIRE 16 -1 (4125 1850)(3775 1850);
WIRE 16 -1 (3775 1775)(3775 1850);
WIRE 16 -1 (3775 1850)(3425 1850);
WIRE 16 -1 (3425 1775)(3425 1850);
WIRE 16 -1 (3425 1850)(3025 1850);
WIRE 16 -1 (3025 1775)(3025 1850);
WIRE 16 -1 (2675 1850)(3025 1850);
WIRE 16 -1 (2675 1850)(2675 1900);
WIRE 16 -1 (2675 1850)(2675 1775);
WIRE 16 -1 (2675 1575)(2675 1425);
WIRE 16 -1 (2675 1425)(3025 1425);
WIRE 16 -1 (3025 1575)(3025 1425);
WIRE 16 -1 (3025 1425)(3425 1425);
WIRE 16 -1 (3425 1575)(3425 1425);
WIRE 16 -1 (3425 1425)(3775 1425);
WIRE 16 -1 (3775 1575)(3775 1425);
WIRE 16 -1 (3775 1425)(4125 1425);
WIRE 16 -1 (4125 1575)(4125 1425);
WIRE 16 -1 (4400 1425)(4125 1425);
WIRE 16 -1 (4400 1425)(4525 1425);
WIRE 16 -1 (4400 1350)(4400 1425);
WIRE 16 -1 (4525 1575)(4525 1425);
WIRE 16 -1 (-1375 1125)(-1050 1125);
WIRE 16 -1 (-1050 1125)(-1050 1325);
WIRE 16 -1 (-1050 1025)(-1050 1125);
WIRE 16 -1 (-1050 825)(-1050 750);
WIRE 16 -1 (-1575 1125)(-1700 1125);
WIRE 16 -1 (-1700 1375)(-1700 1125);
WIRE 16 -1 (-1475 2800)(-1475 2650);
WIRE 16 -1 (-1475 2650)(-1125 2650);
WIRE 16 -1 (-1125 2800)(-1125 2650);
WIRE 16 -1 (-1125 2650)(-775 2650);
WIRE 16 -1 (-775 2800)(-775 2650);
WIRE 16 -1 (-775 2650)(-425 2650);
WIRE 16 -1 (-425 2800)(-425 2650);
WIRE 16 -1 (-425 2600)(-425 2650);
WIRE 16 -1 (-1875 3000)(-1875 3075);
WIRE 16 -1 (-2225 3075)(-1875 3075);
WIRE 16 -1 (-2225 3075)(-2225 3125);
WIRE 16 -1 (-2225 3075)(-2225 3000);
WIRE 16 -1 (3400 1050)(3400 1125);
WIRE 16 -1 (3400 1125)(3000 1125);
WIRE 16 -1 (3000 1050)(3000 1125);
WIRE 16 -1 (2650 1125)(3000 1125);
WIRE 16 -1 (2650 1125)(2650 1175);
WIRE 16 -1 (2650 1125)(2650 1050);
WIRE 16 -1 (2650 850)(2650 700);
WIRE 16 -1 (2650 700)(3000 700);
WIRE 16 -1 (3000 850)(3000 700);
WIRE 16 -1 (3000 700)(3400 700);
WIRE 16 -1 (3400 850)(3400 700);
WIRE 16 -1 (3600 700)(3400 700);
WIRE 16 -1 (3600 650)(3600 700);
WIRE 16 -1 (-425 3000)(-425 3075);
WIRE 16 -1 (-425 3075)(-775 3075);
WIRE 16 -1 (-775 3000)(-775 3075);
WIRE 16 -1 (-775 3075)(-1125 3075);
WIRE 16 -1 (-1125 3000)(-1125 3075);
WIRE 16 -1 (-1125 3075)(-1475 3075);
WIRE 16 -1 (-1475 3000)(-1475 3075);
WIRE 16 -1 (-1475 3075)(-1475 3125);
WIRE 16 -1 (-2225 2800)(-2225 2650);
WIRE 16 -1 (-2225 2650)(-1875 2650);
WIRE 16 -1 (-1875 2800)(-1875 2650);
WIRE 16 -1 (-1875 2575)(-1875 2650);
WIRE 16 -1 (2225 200)(2225 250);
WIRE 16 -1 (2225 250)(1950 250);
WIRE 16 -1 (1950 200)(1950 250);
WIRE 16 -1 (1950 250)(1650 250);
WIRE 16 -1 (1650 200)(1650 250);
WIRE 16 -1 (1650 250)(1350 250);
WIRE 16 -1 (1350 200)(1350 250);
WIRE 16 -1 (1350 250)(1075 250);
WIRE 16 -1 (1075 200)(1075 250);
WIRE 16 -1 (1075 250)(800 250);
WIRE 16 -1 (800 200)(800 250);
WIRE 16 -1 (800 250)(500 250);
WIRE 16 -1 (500 200)(500 250);
WIRE 16 -1 (500 250)(200 250);
WIRE 16 -1 (200 200)(200 250);
WIRE 16 -1 (200 250)(-125 250);
WIRE 16 -1 (-125 200)(-125 250);
WIRE 16 -1 (-125 250)(-400 250);
WIRE 16 -1 (-400 200)(-400 250);
WIRE 16 -1 (-400 250)(-700 250);
WIRE 16 -1 (-700 200)(-700 250);
WIRE 16 -1 (-700 250)(-1000 250);
WIRE 16 -1 (-1000 200)(-1000 250);
WIRE 16 -1 (-1000 250)(-1275 250);
WIRE 16 -1 (-1275 200)(-1275 250);
WIRE 16 -1 (-1550 250)(-1275 250);
WIRE 16 -1 (-1550 200)(-1550 250);
WIRE 16 -1 (-1850 250)(-1550 250);
WIRE 16 -1 (-1850 200)(-1850 250);
WIRE 16 -1 (-2150 250)(-1850 250);
WIRE 16 -1 (-2150 200)(-2150 250);
WIRE 16 -1 (-2150 250)(-2150 300);
WIRE 16 -1 (2225 0)(2225 -75);
WIRE 16 -1 (2225 -75)(1950 -75);
WIRE 16 -1 (1950 0)(1950 -75);
WIRE 16 -1 (1950 -75)(1650 -75);
WIRE 16 -1 (1650 0)(1650 -75);
WIRE 16 -1 (1650 -75)(1350 -75);
WIRE 16 -1 (1350 0)(1350 -75);
WIRE 16 -1 (1350 -75)(1075 -75);
WIRE 16 -1 (1075 0)(1075 -75);
WIRE 16 -1 (1075 -75)(800 -75);
WIRE 16 -1 (800 0)(800 -75);
WIRE 16 -1 (800 -75)(500 -75);
WIRE 16 -1 (500 0)(500 -75);
WIRE 16 -1 (500 -75)(200 -75);
WIRE 16 -1 (200 0)(200 -75);
WIRE 16 -1 (200 -75)(-125 -75);
WIRE 16 -1 (-125 0)(-125 -75);
WIRE 16 -1 (-125 -75)(-400 -75);
WIRE 16 -1 (-400 0)(-400 -75);
WIRE 16 -1 (-400 -75)(-700 -75);
WIRE 16 -1 (-700 0)(-700 -75);
WIRE 16 -1 (-700 -75)(-1000 -75);
WIRE 16 -1 (-1000 0)(-1000 -75);
WIRE 16 -1 (-1000 -75)(-1275 -75);
WIRE 16 -1 (-1275 0)(-1275 -75);
WIRE 16 -1 (-1550 -75)(-1275 -75);
WIRE 16 -1 (-1550 0)(-1550 -75);
WIRE 16 -1 (-1550 -75)(-1850 -75);
WIRE 16 -1 (-1850 0)(-1850 -75);
WIRE 16 -1 (-1850 -75)(-2150 -75);
WIRE 16 -1 (-2150 0)(-2150 -75);
WIRE 16 -1 (-2150 -75)(-2150 -125);
WIRE 16 -1 (2225 -550)(2225 -500);
WIRE 16 -1 (2225 -500)(1950 -500);
WIRE 16 -1 (1950 -550)(1950 -500);
WIRE 16 -1 (1950 -500)(1650 -500);
WIRE 16 -1 (1650 -550)(1650 -500);
WIRE 16 -1 (1650 -500)(1350 -500);
WIRE 16 -1 (1350 -550)(1350 -500);
WIRE 16 -1 (1350 -500)(1075 -500);
WIRE 16 -1 (1075 -550)(1075 -500);
WIRE 16 -1 (1075 -500)(800 -500);
WIRE 16 -1 (800 -550)(800 -500);
WIRE 16 -1 (800 -500)(500 -500);
WIRE 16 -1 (500 -550)(500 -500);
WIRE 16 -1 (500 -500)(200 -500);
WIRE 16 -1 (200 -550)(200 -500);
WIRE 16 -1 (200 -500)(-125 -500);
WIRE 16 -1 (-125 -550)(-125 -500);
WIRE 16 -1 (-125 -500)(-400 -500);
WIRE 16 -1 (-400 -550)(-400 -500);
WIRE 16 -1 (-400 -500)(-700 -500);
WIRE 16 -1 (-700 -550)(-700 -500);
WIRE 16 -1 (-700 -500)(-1000 -500);
WIRE 16 -1 (-1000 -550)(-1000 -500);
WIRE 16 -1 (-1000 -500)(-1275 -500);
WIRE 16 -1 (-1275 -550)(-1275 -500);
WIRE 16 -1 (-1550 -500)(-1275 -500);
WIRE 16 -1 (-1550 -550)(-1550 -500);
WIRE 16 -1 (-1850 -500)(-1550 -500);
WIRE 16 -1 (-1850 -550)(-1850 -500);
WIRE 16 -1 (-2150 -500)(-1850 -500);
WIRE 16 -1 (-2150 -550)(-2150 -500);
WIRE 16 -1 (-2150 -500)(-2150 -450);
WIRE 16 -1 (2225 -750)(2225 -825);
WIRE 16 -1 (2225 -825)(1950 -825);
WIRE 16 -1 (1950 -750)(1950 -825);
WIRE 16 -1 (1950 -825)(1650 -825);
WIRE 16 -1 (1650 -750)(1650 -825);
WIRE 16 -1 (1650 -825)(1350 -825);
WIRE 16 -1 (1350 -750)(1350 -825);
WIRE 16 -1 (1350 -825)(1075 -825);
WIRE 16 -1 (1075 -750)(1075 -825);
WIRE 16 -1 (1075 -825)(800 -825);
WIRE 16 -1 (800 -750)(800 -825);
WIRE 16 -1 (800 -825)(500 -825);
WIRE 16 -1 (500 -750)(500 -825);
WIRE 16 -1 (500 -825)(200 -825);
WIRE 16 -1 (200 -750)(200 -825);
WIRE 16 -1 (200 -825)(-125 -825);
WIRE 16 -1 (-125 -750)(-125 -825);
WIRE 16 -1 (-125 -825)(-400 -825);
WIRE 16 -1 (-400 -750)(-400 -825);
WIRE 16 -1 (-400 -825)(-700 -825);
WIRE 16 -1 (-700 -750)(-700 -825);
WIRE 16 -1 (-700 -825)(-1000 -825);
WIRE 16 -1 (-1000 -750)(-1000 -825);
WIRE 16 -1 (-1000 -825)(-1275 -825);
WIRE 16 -1 (-1275 -750)(-1275 -825);
WIRE 16 -1 (-1550 -825)(-1275 -825);
WIRE 16 -1 (-1550 -750)(-1550 -825);
WIRE 16 -1 (-1550 -825)(-1850 -825);
WIRE 16 -1 (-1850 -750)(-1850 -825);
WIRE 16 -1 (-1850 -825)(-2150 -825);
WIRE 16 -1 (-2150 -750)(-2150 -825);
WIRE 16 -1 (-2150 -825)(-2150 -875);
WIRE 16 -1 (-50 1625)(-175 1625);
WIRE 16 -1 (-50 1450)(-50 1625);
WIRE 16 -1 (-25 2225)(-25 2075);
WIRE 16 -1 (-25 2075)(-150 2075);
WIRE 16 -1 (4550 -75)(4550 25);
WIRE 16 -1 (4175 25)(4550 25);
WIRE 16 -1 (4175 -75)(4175 25);
WIRE 16 -1 (3775 25)(4175 25);
WIRE 16 -1 (3775 -50)(3775 25);
WIRE 16 -1 (3350 25)(3775 25);
WIRE 16 -1 (3350 -50)(3350 25);
WIRE 16 -1 (2925 25)(3350 25);
WIRE 16 -1 (2925 -50)(2925 25);
WIRE 16 -1 (2925 25)(2925 100);
WIRE 16 -1 (4550 -275)(4550 -400);
WIRE 16 -1 (4175 -400)(4550 -400);
WIRE 16 -1 (4175 -275)(4175 -400);
WIRE 16 -1 (4175 -400)(3775 -400);
WIRE 16 -1 (3775 -250)(3775 -400);
WIRE 16 -1 (3775 -400)(3350 -400);
WIRE 16 -1 (3350 -250)(3350 -400);
WIRE 16 -1 (3350 -400)(2925 -400);
WIRE 16 -1 (2925 -400)(2925 -250);
WIRE 16 -1 (2925 -400)(2925 -525);
WIRE 16 -1 (5000 2925)(5000 3000);
WIRE 16 -1 (5000 3000)(4600 3000);
WIRE 16 -1 (4600 2925)(4600 3000);
WIRE 16 -1 (4600 3000)(4250 3000);
WIRE 16 -1 (4250 2925)(4250 3000);
WIRE 16 -1 (4250 3000)(3850 3000);
WIRE 16 -1 (3850 2925)(3850 3000);
WIRE 16 -1 (3850 3000)(3500 3000);
WIRE 16 -1 (3500 2925)(3500 3000);
WIRE 16 -1 (3500 3000)(3150 3000);
WIRE 16 -1 (3150 2925)(3150 3000);
WIRE 16 -1 (3150 3000)(2750 3000);
WIRE 16 -1 (2750 2925)(2750 3000);
WIRE 16 -1 (2400 3000)(2750 3000);
WIRE 16 -1 (2400 3000)(2400 2925);
WIRE 16 -1 (2400 3000)(2400 3050);
WIRE 16 -1 (2400 2725)(2400 2575);
WIRE 16 -1 (2400 2575)(2750 2575);
WIRE 16 -1 (2750 2725)(2750 2575);
WIRE 16 -1 (2750 2575)(3150 2575);
WIRE 16 -1 (3150 2725)(3150 2575);
WIRE 16 -1 (3150 2575)(3500 2575);
WIRE 16 -1 (3500 2725)(3500 2575);
WIRE 16 -1 (3500 2575)(3850 2575);
WIRE 16 -1 (3850 2725)(3850 2575);
WIRE 16 -1 (4125 2575)(3850 2575);
WIRE 16 -1 (4125 2575)(4250 2575);
WIRE 16 -1 (4125 2500)(4125 2575);
WIRE 16 -1 (4250 2575)(4600 2575);
WIRE 16 -1 (4250 2725)(4250 2575);
WIRE 16 -1 (4600 2575)(5000 2575);
WIRE 16 -1 (4600 2725)(4600 2575);
WIRE 16 -1 (5000 2725)(5000 2575);
WIRE 16 2175 (2200 3325)(5400 3325);
WIRE 16 2175 (2200 475)(2200 3325);
WIRE 16 2175 (5400 3325)(5400 475);
WIRE 16 2175 (5400 475)(2200 475);
WIRE 16 682 (-100 3400)(-100 2425);
WIRE 16 682 (-100 3400)(-2425 3400);
WIRE 16 682 (-100 2425)(-2425 2425);
WIRE 16 682 (-2425 2425)(-2425 3400);
WIRE 16 2175 (2250 2225)(5325 2225);
WIRE 16 682 (5225 300)(2750 300);
WIRE 16 682 (5225 -700)(5225 300);
WIRE 16 682 (2750 300)(2750 -700);
WIRE 16 682 (2750 -700)(5225 -700);
WIRE 16 -1 (-450 2075)(-700 2075);
WIRE 16 -1 (-700 2075)(-800 2075);
WIRE 16 -1 (-700 1925)(-700 2075);
WIRE 16 -1 (-800 2075)(-800 1925);
WIRE 16 -1 (-800 1925)(-1200 1925);
WIRE 16 -1 (-1200 1925)(-1200 2050);
WIRE 16 -1 (-1200 2050)(-1925 2050);
FORCEPROP 2 LAST SIG_NAME VSENSE_PVDDQ_DEF_P
J 0
(-1930 2065);
DISPLAY 0.617021 (-1930 2065);
PAINT ORANGE (-1930 2065);
WIRE 16 -1 (-700 1725)(-700 1625);
WIRE 16 -1 (-475 1625)(-700 1625);
WIRE 16 -1 (-700 1625)(-800 1625);
WIRE 16 -1 (-800 1850)(-800 1625);
WIRE 16 -1 (-1200 1850)(-800 1850);
WIRE 16 -1 (-1200 1800)(-1200 1850);
WIRE 16 -1 (-1925 1800)(-1200 1800);
FORCEPROP 2 LAST SIG_NAME VSENSE_PVDDQ_DEF_N
J 0
(-1935 1810);
DISPLAY 0.617021 (-1935 1810);
PAINT ORANGE (-1935 1810);
DOT 1 (-2150 -825);
DOT 1 (-2150 -500);
DOT 1 (-2150 -75);
DOT 1 (-1850 -825);
DOT 1 (-1550 -825);
DOT 1 (-1850 -500);
DOT 1 (-1550 -500);
DOT 1 (-1850 -75);
DOT 1 (-1550 -75);
DOT 1 (-1275 -825);
DOT 1 (-1275 -500);
DOT 1 (-1275 -75);
DOT 1 (-1000 -825);
DOT 1 (-700 -825);
DOT 1 (-1000 -500);
DOT 1 (-700 -500);
DOT 1 (-1000 -75);
DOT 1 (-700 -75);
DOT 1 (-400 -825);
DOT 1 (-125 -825);
DOT 1 (-400 -500);
DOT 1 (-125 -500);
DOT 1 (-400 -75);
DOT 1 (-125 -75);
DOT 1 (-2150 250);
DOT 1 (-2225 3075);
DOT 1 (-1850 250);
DOT 1 (-1550 250);
DOT 1 (-1275 250);
DOT 1 (-1050 1125);
DOT 1 (-1000 250);
DOT 1 (-700 250);
DOT 1 (-400 250);
DOT 1 (-125 250);
DOT 1 (-700 1625);
DOT 1 (-1875 2650);
DOT 1 (-1125 2650);
DOT 1 (-1475 3075);
DOT 1 (-1125 3075);
DOT 1 (-700 2075);
DOT 1 (-775 2650);
DOT 1 (-425 2650);
DOT 1 (-775 3075);
DOT 1 (200 -825);
DOT 1 (500 -825);
DOT 1 (200 -500);
DOT 1 (500 -500);
DOT 1 (200 -75);
DOT 1 (500 -75);
DOT 1 (800 -825);
DOT 1 (800 -500);
DOT 1 (800 -75);
DOT 1 (1075 -825);
DOT 1 (1350 -825);
DOT 1 (1075 -500);
DOT 1 (1350 -500);
DOT 1 (1075 -75);
DOT 1 (1350 -75);
DOT 1 (1650 -825);
DOT 1 (1950 -825);
DOT 1 (1650 -500);
DOT 1 (1950 -500);
DOT 1 (1650 -75);
DOT 1 (1950 -75);
DOT 1 (2925 -400);
DOT 1 (3350 -400);
DOT 1 (3775 -400);
DOT 1 (4175 -400);
DOT 1 (200 250);
DOT 1 (500 250);
DOT 1 (800 250);
DOT 1 (1075 250);
DOT 1 (1350 250);
DOT 1 (1650 250);
DOT 1 (1950 250);
DOT 1 (2925 25);
DOT 1 (3000 700);
DOT 1 (2650 1125);
DOT 1 (3000 1125);
DOT 1 (3025 1425);
DOT 1 (2675 1850);
DOT 1 (3025 1850);
DOT 1 (3350 25);
DOT 1 (3400 700);
DOT 1 (3775 25);
DOT 1 (3425 1425);
DOT 1 (3425 1850);
DOT 1 (3775 1425);
DOT 1 (3775 1850);
DOT 1 (2400 3000);
DOT 1 (2750 2575);
DOT 1 (2750 3000);
DOT 1 (3150 2575);
DOT 1 (3150 3000);
DOT 1 (3500 2575);
DOT 1 (3500 3000);
DOT 1 (3850 2575);
DOT 1 (3850 3000);
DOT 1 (4175 25);
DOT 1 (4125 1425);
DOT 1 (4400 1425);
DOT 1 (4125 1850);
DOT 1 (4125 2575);
DOT 1 (4250 2575);
DOT 1 (4250 3000);
DOT 1 (4600 2575);
DOT 1 (4600 3000);
FORCENOTE
BOTTOM SIDE: 805
(-2179 3092) 0;
DISPLAY LEFT (-2179 3092);
DISPLAY 0.638298 (-2179 3092);
PAINT PURPLE (-2179 3092);
FORCENOTE
ROOM=VDDQ_DEF_CPU0
(-2325 2425) 0;
DISPLAY LEFT (-2325 2425);
DISPLAY 1.021277 (-2325 2425);
PAINT PURPLE (-2325 2425);
FORCENOTE
INPUT FILTER
(-1780 830) 0;
DISPLAY LEFT (-1780 830);
PAINT PURPLE (-1780 830);
FORCENOTE
PVDDQ_DEF VOLTAGE SENSE
(-1895 1530) 0;
DISPLAY LEFT (-1895 1530);
PAINT PURPLE (-1895 1530);
FORCENOTE
ROUT AS DIFF PAIR
(-1220 1880) 0;
DISPLAY LEFT (-1220 1880);
DISPLAY 0.808511 (-1220 1880);
PAINT PURPLE (-1220 1880);
FORCENOTE
10MIL WIDTH
(-1145 1780) 0;
DISPLAY LEFT (-1145 1780);
DISPLAY 0.808511 (-1145 1780);
PAINT PURPLE (-1145 1780);
FORCENOTE
5MIL SPACING
(-1170 1730) 0;
DISPLAY LEFT (-1170 1730);
DISPLAY 0.808511 (-1170 1730);
PAINT PURPLE (-1170 1730);
FORCENOTE
TOP SIDE: 603
(-1198 3092) 0;
DISPLAY LEFT (-1198 3092);
DISPLAY 0.638298 (-1198 3092);
PAINT PURPLE (-1198 3092);
FORCENOTE
PVDDQ CPU CAVITY CAPS
(-1350 2425) 0;
DISPLAY LEFT (-1350 2425);
DISPLAY 1.021277 (-1350 2425);
PAINT PURPLE (-1350 2425);
FORCENOTE
ROOM = PVDDQ_DEF_PWR_VR
(-2465 -1310) 0;
DISPLAY LEFT (-2465 -1310);
DISPLAY 2.446809 (-2465 -1310);
PAINT PURPLE (-2465 -1310);
FORCENOTE
CAD NOTE:
(3125 -550) 0;
DISPLAY LEFT (3125 -550);
DISPLAY 1.021277 (3125 -550);
PAINT PURPLE (3125 -550);
FORCENOTE
PLACE NEAR VR OUTPUT INDUCTORS
(3150 -625) 0;
DISPLAY LEFT (3150 -625);
DISPLAY 1.021277 (3150 -625);
PAINT PURPLE (3150 -625);
FORCENOTE
CAPS TO BE PLACED BETWEEN DIMMS
(2295 3255) 0;
DISPLAY LEFT (2295 3255);
DISPLAY 1.021277 (2295 3255);
PAINT PURPLE (2295 3255);
QUIT
